FILE_TYPE = MACRO_DRAWING;
SET COLOR_WIRE YELLOW;
SET COLOR_PROP ORANGE;
SET COLOR_DOT WHITE;
SET COLOR_ARC YELLOW;
SET COLOR_BODY GREEN;
SET COLOR_NOTE PURPLE;
SET PROP_DISPLAY VALUE;
SET PAGE_NUMBER P267;
FORCEADD UNIVERSAL_GND..1
(-10850 2275);
FORCEPROP 3 LASTPIN (-10850 2325) SIG_NAME GND\g
J 0
(-10840 2335);
DISPLAY 0.659574 (-10840 2335);
PAINT MONO (-10840 2335);
DISPLAY INVISIBLE (-10840 2335);
FORCEPROP 2 LAST CDS_LIB logical_power
J 0
(-10850 2275);
DISPLAY INVISIBLE (-10850 2275);
FORCEPROP 1 LAST HDL_POWER GND
J 1
(-10825 2200);
DISPLAY 0.872340 (-10825 2200);
PAINT GREEN (-10825 2200);
DISPLAY INVISIBLE (-10825 2200);
FORCEPROP 1 LAST PATH I1
J 0
(-10775 2275);
DISPLAY 0.872340 (-10775 2275);
PAINT AQUA (-10775 2275);
DISPLAY INVISIBLE (-10775 2275);
FORCEADD Q_CAP..1
(-10975 4350);
FORCEPROP 1 LAST PART_NUMBER CH6223MEA01
J 0
(-10925 4150);
DISPLAY 0.617021 (-10925 4150);
PAINT BLUE (-10925 4150);
DISPLAY INVISIBLE (-10925 4150);
FORCEPROP 1 LAST MATERIAL X6S
J 0
(-10925 4250);
DISPLAY 0.617021 (-10925 4250);
PAINT RED (-10925 4250);
FORCEPROP 1 LAST VOLTAGE 16V
J 0
(-10925 4350);
DISPLAY 0.617021 (-10925 4350);
PAINT SKYBLUE (-10925 4350);
FORCEPROP 1 LAST VALUE 22UF
J 0
(-10925 4400);
DISPLAY 0.617021 (-10925 4400);
PAINT SKYBLUE (-10925 4400);
FORCEPROP 1 LAST TOLERANCE 20%
J 0
(-10925 4300);
DISPLAY 0.617021 (-10925 4300);
PAINT SKYBLUE (-10925 4300);
FORCEPROP 1 LAST PACK_TYPE C0805
J 0
(-10925 4200);
DISPLAY 0.617021 (-10925 4200);
PAINT SKYBLUE (-10925 4200);
FORCEPROP 1 LAST LOCATION PC1247
J 0
(-10925 4450);
DISPLAY 0.617021 (-10925 4450);
PAINT AQUA (-10925 4450);
FORCEPROP 1 LASTPIN (-10975 4450) $PN 1
J 0
(-10965 4430);
DISPLAY 0.617021 (-10965 4430);
PAINT MONO (-10965 4430);
FORCEPROP 1 LASTPIN (-10975 4250) $PN 2
J 0
(-10965 4230);
DISPLAY 0.617021 (-10965 4230);
PAINT MONO (-10965 4230);
FORCEPROP 2 LAST BOM_COST VR_PCH
J 0
(-10925 4500);
DISPLAY 0.680851 (-10925 4500);
DISPLAY INVISIBLE (-10925 4500);
FORCEPROP 2 LAST CDS_LIB pure_quanta
J 0
(-10975 4350);
DISPLAY INVISIBLE (-10975 4350);
FORCEPROP 1 LAST PATH I10
J 0
(-10925 4500);
DISPLAY 0.978723 (-10925 4500);
PAINT WHITE (-10925 4500);
DISPLAY INVISIBLE (-10925 4500);
FORCEPROP 2 LAST $SEC 1
J 0
(-10925 4550);
DISPLAY 0.680851 (-10925 4550);
PAINT MONO (-10925 4550);
DISPLAY INVISIBLE (-10925 4550);
FORCEPROP 2 LAST CDS_SEC 1
J 0
(-10925 4550);
DISPLAY 1.021277 (-10925 4550);
DISPLAY INVISIBLE (-10925 4550);
FORCEADD UNIVERSAL_GND..1
(-9775 2275);
FORCEPROP 3 LASTPIN (-9775 2325) SIG_NAME GND\g
J 0
(-9765 2335);
DISPLAY 0.659574 (-9765 2335);
PAINT MONO (-9765 2335);
DISPLAY INVISIBLE (-9765 2335);
FORCEPROP 2 LAST CDS_LIB logical_power
J 0
(-9775 2275);
DISPLAY INVISIBLE (-9775 2275);
FORCEPROP 1 LAST HDL_POWER GND
J 1
(-9750 2200);
DISPLAY 0.872340 (-9750 2200);
PAINT GREEN (-9750 2200);
DISPLAY INVISIBLE (-9750 2200);
FORCEPROP 1 LAST PATH I11
J 0
(-9700 2275);
DISPLAY 0.872340 (-9700 2275);
PAINT AQUA (-9700 2275);
DISPLAY INVISIBLE (-9700 2275);
FORCEADD Q_CAP..1
R 2
(-10375 3400);
FORCEPROP 1 LAST PART_NUMBER TMP_QCH21006JB10
J 2
(-10425 3275);
DISPLAY 0.617021 (-10425 3275);
PAINT BLUE (-10425 3275);
DISPLAY INVISIBLE (-10425 3275);
FORCEPROP 1 LAST PACK_TYPE 0402
J 2
(-10425 3225);
DISPLAY 0.617021 (-10425 3225);
PAINT SKYBLUE (-10425 3225);
FORCEPROP 1 LAST VOLTAGE 50V
J 2
(-10425 3425);
DISPLAY 0.617021 (-10425 3425);
PAINT SKYBLUE (-10425 3425);
FORCEPROP 1 LAST TOLERANCE 5%
J 2
(-10425 3375);
DISPLAY 0.617021 (-10425 3375);
PAINT SKYBLUE (-10425 3375);
FORCEPROP 1 LAST VALUE 1000PF
J 2
(-10425 3475);
DISPLAY 0.617021 (-10425 3475);
PAINT SKYBLUE (-10425 3475);
FORCEPROP 1 LAST MATERIAL EMPTY
J 2
(-10425 3325);
DISPLAY 0.617021 (-10425 3325);
PAINT RED (-10425 3325);
FORCEPROP 1 LAST LOCATION C1300
J 2
(-10425 3525);
DISPLAY 0.723404 (-10425 3525);
PAINT AQUA (-10425 3525);
FORCEPROP 1 LASTPIN (-10375 3500) $PN 1
J 2
(-10385 3480);
DISPLAY 0.617021 (-10385 3480);
FORCEPROP 1 LASTPIN (-10375 3300) $PN 2
J 2
(-10385 3280);
DISPLAY 0.617021 (-10385 3280);
FORCEPROP 2 LAST CDS_LIB pure_quanta
J 0
(-10375 3400);
PAINT MONO (-10375 3400);
DISPLAY INVISIBLE (-10375 3400);
FORCEPROP 1 LAST PATH I12
J 2
(-10425 3550);
DISPLAY 0.978723 (-10425 3550);
PAINT WHITE (-10425 3550);
DISPLAY INVISIBLE (-10425 3550);
FORCEPROP 2 LAST $SEC 1
J 0
(-10425 3600);
DISPLAY 0.680851 (-10425 3600);
PAINT MONO (-10425 3600);
DISPLAY INVISIBLE (-10425 3600);
FORCEPROP 2 LAST CDS_SEC 1
J 0
(-10425 3600);
DISPLAY 1.021277 (-10425 3600);
DISPLAY INVISIBLE (-10425 3600);
FORCEADD UNIVERSAL_GND..1
(-10275 3175);
FORCEPROP 3 LASTPIN (-10275 3225) SIG_NAME GND\g
J 0
(-10265 3235);
DISPLAY 0.659574 (-10265 3235);
PAINT MONO (-10265 3235);
DISPLAY INVISIBLE (-10265 3235);
FORCEPROP 2 LAST CDS_LIB logical_power
J 0
(-10275 3175);
PAINT MONO (-10275 3175);
DISPLAY INVISIBLE (-10275 3175);
FORCEPROP 1 LAST HDL_POWER GND
J 1
(-10250 3100);
DISPLAY 0.872340 (-10250 3100);
PAINT GREEN (-10250 3100);
DISPLAY INVISIBLE (-10250 3100);
FORCEPROP 1 LAST PATH I13
J 0
(-10200 3175);
DISPLAY 0.872340 (-10200 3175);
PAINT AQUA (-10200 3175);
DISPLAY INVISIBLE (-10200 3175);
FORCEADD Q_RES..2
(-10275 3400);
FORCEPROP 1 LAST PART_NUMBER CS22002FB07
J 0
(-10235 3275);
DISPLAY 0.617021 (-10235 3275);
PAINT BLUE (-10235 3275);
DISPLAY INVISIBLE (-10235 3275);
FORCEPROP 1 LAST WATTAGE 1/16W
J 0
(-10235 3375);
DISPLAY 0.617021 (-10235 3375);
PAINT SKYBLUE (-10235 3375);
FORCEPROP 1 LAST VALUE 2K
J 0
(-10230 3475);
DISPLAY 0.617021 (-10230 3475);
PAINT SKYBLUE (-10230 3475);
FORCEPROP 1 LAST TOLERANCE 1%
J 0
(-10230 3425);
DISPLAY 0.617021 (-10230 3425);
PAINT SKYBLUE (-10230 3425);
FORCEPROP 1 LAST MATERIAL CHIP
J 0
(-10235 3325);
DISPLAY 0.617021 (-10235 3325);
PAINT SKYBLUE (-10235 3325);
FORCEPROP 1 LAST PACK_TYPE 0402LF
J 0
(-10235 3225);
DISPLAY 0.617021 (-10235 3225);
PAINT SKYBLUE (-10235 3225);
FORCEPROP 1 LAST LOCATION R2332
J 0
(-10230 3525);
DISPLAY 0.723404 (-10230 3525);
PAINT AQUA (-10230 3525);
FORCEPROP 1 LASTPIN (-10275 3500) $PN 1
J 0
(-10270 3462);
DISPLAY 0.617021 (-10270 3462);
FORCEPROP 1 LASTPIN (-10275 3300) $PN 2
J 0
(-10270 3310);
DISPLAY 0.617021 (-10270 3310);
FORCEPROP 2 LAST CDS_LIB pure_quanta
J 0
(-10275 3400);
PAINT MONO (-10275 3400);
DISPLAY INVISIBLE (-10275 3400);
FORCEPROP 1 LAST PATH I14
J 0
(-10225 3575);
DISPLAY 0.978723 (-10225 3575);
PAINT WHITE (-10225 3575);
DISPLAY INVISIBLE (-10225 3575);
FORCEPROP 2 LAST $SEC 1
J 0
(-10225 3625);
DISPLAY 0.680851 (-10225 3625);
PAINT MONO (-10225 3625);
DISPLAY INVISIBLE (-10225 3625);
FORCEPROP 2 LAST CDS_SEC 1
J 0
(-10225 3625);
DISPLAY 1.021277 (-10225 3625);
DISPLAY INVISIBLE (-10225 3625);
FORCEADD Q_RES..2
(-9775 2525);
FORCEPROP 1 LAST PART_NUMBER CS29762FB05
J 0
(-9735 2400);
DISPLAY 0.617021 (-9735 2400);
PAINT BLUE (-9735 2400);
DISPLAY INVISIBLE (-9735 2400);
FORCEPROP 1 LAST VALUE 9.76K
J 0
(-9730 2600);
DISPLAY 0.617021 (-9730 2600);
PAINT SKYBLUE (-9730 2600);
FORCEPROP 1 LAST MATERIAL CHIP
J 0
(-9735 2450);
DISPLAY 0.617021 (-9735 2450);
PAINT RED (-9735 2450);
FORCEPROP 1 LAST PACK_TYPE 0402LF
J 0
(-9735 2350);
DISPLAY 0.617021 (-9735 2350);
PAINT SKYBLUE (-9735 2350);
FORCEPROP 1 LAST WATTAGE 1/16W
J 0
(-9735 2500);
DISPLAY 0.617021 (-9735 2500);
PAINT SKYBLUE (-9735 2500);
FORCEPROP 1 LAST TOLERANCE 1%
J 0
(-9730 2550);
DISPLAY 0.617021 (-9730 2550);
PAINT SKYBLUE (-9730 2550);
FORCEPROP 1 LAST LOCATION PR1336
J 0
(-9730 2650);
DISPLAY 0.617021 (-9730 2650);
PAINT AQUA (-9730 2650);
FORCEPROP 1 LASTPIN (-9775 2625) $PN 1
J 0
(-9770 2587);
DISPLAY 0.617021 (-9770 2587);
PAINT MONO (-9770 2587);
FORCEPROP 1 LASTPIN (-9775 2425) $PN 2
J 0
(-9770 2435);
DISPLAY 0.617021 (-9770 2435);
PAINT MONO (-9770 2435);
FORCEPROP 2 LAST CDS_LIB pure_quanta
J 0
(-9775 2525);
DISPLAY INVISIBLE (-9775 2525);
FORCEPROP 1 LAST PATH I15
J 0
(-9725 2700);
DISPLAY 0.978723 (-9725 2700);
PAINT WHITE (-9725 2700);
DISPLAY INVISIBLE (-9725 2700);
FORCEPROP 0 LAST $SEC 1
J 0
(-9725 2700);
DISPLAY 0.680851 (-9725 2700);
PAINT MONO (-9725 2700);
DISPLAY INVISIBLE (-9725 2700);
FORCEPROP 0 LAST CDS_SEC 1
J 0
(-9725 2700);
DISPLAY 1.021277 (-9725 2700);
DISPLAY INVISIBLE (-9725 2700);
FORCEADD Q_CAP..1
(-10550 4350);
FORCEPROP 1 LAST PART_NUMBER CH6223MEA01
J 0
(-10500 4150);
DISPLAY 0.617021 (-10500 4150);
PAINT BLUE (-10500 4150);
DISPLAY INVISIBLE (-10500 4150);
FORCEPROP 1 LAST PACK_TYPE C0805
J 0
(-10500 4200);
DISPLAY 0.617021 (-10500 4200);
PAINT SKYBLUE (-10500 4200);
FORCEPROP 1 LAST VOLTAGE 16V
J 0
(-10500 4350);
DISPLAY 0.617021 (-10500 4350);
PAINT SKYBLUE (-10500 4350);
FORCEPROP 1 LAST VALUE 22UF
J 0
(-10500 4400);
DISPLAY 0.617021 (-10500 4400);
PAINT SKYBLUE (-10500 4400);
FORCEPROP 1 LAST TOLERANCE 20%
J 0
(-10500 4300);
DISPLAY 0.617021 (-10500 4300);
PAINT SKYBLUE (-10500 4300);
FORCEPROP 1 LAST MATERIAL X6S
J 0
(-10500 4250);
DISPLAY 0.617021 (-10500 4250);
PAINT RED (-10500 4250);
FORCEPROP 1 LAST LOCATION PC1248
J 0
(-10500 4450);
DISPLAY 0.617021 (-10500 4450);
PAINT AQUA (-10500 4450);
FORCEPROP 1 LASTPIN (-10550 4450) $PN 1
J 0
(-10540 4430);
DISPLAY 0.617021 (-10540 4430);
PAINT MONO (-10540 4430);
FORCEPROP 1 LASTPIN (-10550 4250) $PN 2
J 0
(-10540 4230);
DISPLAY 0.617021 (-10540 4230);
PAINT MONO (-10540 4230);
FORCEPROP 2 LAST BOM_COST VR_PCH
J 0
(-10500 4500);
DISPLAY 0.680851 (-10500 4500);
DISPLAY INVISIBLE (-10500 4500);
FORCEPROP 2 LAST CDS_LIB pure_quanta
J 0
(-10550 4350);
DISPLAY INVISIBLE (-10550 4350);
FORCEPROP 1 LAST PATH I16
J 0
(-10500 4500);
DISPLAY 0.978723 (-10500 4500);
PAINT WHITE (-10500 4500);
DISPLAY INVISIBLE (-10500 4500);
FORCEPROP 2 LAST $SEC 1
J 0
(-10500 4550);
DISPLAY 0.680851 (-10500 4550);
PAINT MONO (-10500 4550);
DISPLAY INVISIBLE (-10500 4550);
FORCEPROP 2 LAST CDS_SEC 1
J 0
(-10500 4550);
DISPLAY 1.021277 (-10500 4550);
DISPLAY INVISIBLE (-10500 4550);
FORCEADD Q_CAP..1
(-10125 4350);
FORCEPROP 1 LAST PART_NUMBER CH5103KEB01
J 0
(-10075 4200);
DISPLAY 0.617021 (-10075 4200);
PAINT BLUE (-10075 4200);
DISPLAY INVISIBLE (-10075 4200);
FORCEPROP 1 LAST VOLTAGE 16V
J 0
(-10075 4350);
DISPLAY 0.617021 (-10075 4350);
PAINT SKYBLUE (-10075 4350);
FORCEPROP 1 LAST VALUE 1UF
J 0
(-10075 4400);
DISPLAY 0.617021 (-10075 4400);
PAINT SKYBLUE (-10075 4400);
FORCEPROP 1 LAST PACK_TYPE C0402
J 0
(-10075 4150);
DISPLAY 0.617021 (-10075 4150);
PAINT SKYBLUE (-10075 4150);
FORCEPROP 1 LAST MATERIAL X6S
J 0
(-10075 4250);
DISPLAY 0.617021 (-10075 4250);
PAINT RED (-10075 4250);
FORCEPROP 1 LAST TOLERANCE 10%
J 0
(-10075 4300);
DISPLAY 0.617021 (-10075 4300);
PAINT SKYBLUE (-10075 4300);
FORCEPROP 1 LAST LOCATION PC1249
J 0
(-10075 4450);
DISPLAY 0.617021 (-10075 4450);
PAINT AQUA (-10075 4450);
FORCEPROP 1 LASTPIN (-10125 4450) $PN 1
J 0
(-10115 4430);
DISPLAY 0.617021 (-10115 4430);
PAINT MONO (-10115 4430);
FORCEPROP 1 LASTPIN (-10125 4250) $PN 2
J 0
(-10115 4230);
DISPLAY 0.617021 (-10115 4230);
PAINT MONO (-10115 4230);
FORCEPROP 2 LAST CDS_LIB pure_quanta
J 0
(-10125 4350);
DISPLAY INVISIBLE (-10125 4350);
FORCEPROP 1 LAST PATH I17
J 0
(-10075 4500);
DISPLAY 0.978723 (-10075 4500);
PAINT WHITE (-10075 4500);
DISPLAY INVISIBLE (-10075 4500);
FORCEPROP 2 LAST $SEC 1
J 0
(-10075 4550);
DISPLAY 0.680851 (-10075 4550);
PAINT MONO (-10075 4550);
DISPLAY INVISIBLE (-10075 4550);
FORCEPROP 2 LAST CDS_SEC 1
J 0
(-10075 4550);
DISPLAY 1.021277 (-10075 4550);
DISPLAY INVISIBLE (-10075 4550);
FORCEADD Q_RES..1
(-9650 3350);
FORCEPROP 1 LAST PART_NUMBER CS33012FB03
J 0
(-9550 3300);
DISPLAY 0.638298 (-9550 3300);
DISPLAY INVISIBLE (-9550 3300);
FORCEPROP 1 LAST PACK_TYPE 0402LF
J 0
(-9550 3250);
DISPLAY 0.638298 (-9550 3250);
FORCEPROP 1 LAST WATTAGE 1/16W
J 2
(-9575 3250);
DISPLAY 0.638298 (-9575 3250);
FORCEPROP 1 LAST MATERIAL CHIP
J 0
(-9700 3300);
DISPLAY 0.638298 (-9700 3300);
FORCEPROP 1 LAST VALUE 30.1K
J 2
(-9725 3375);
DISPLAY 0.638298 (-9725 3375);
FORCEPROP 1 LAST LOCATION PR3335
J 0
(-9850 3300);
DISPLAY 0.638298 (-9850 3300);
FORCEPROP 1 LASTPIN (-9750 3350) $PN 1
J 0
(-9738 3362);
DISPLAY 0.787234 (-9738 3362);
PAINT MONO (-9738 3362);
FORCEPROP 1 LASTPIN (-9550 3350) $PN 2
J 0
(-9588 3362);
DISPLAY 0.787234 (-9588 3362);
PAINT MONO (-9588 3362);
FORCEPROP 1 LAST TOLERANCE 1%
J 0
(-9525 3375);
DISPLAY 0.638298 (-9525 3375);
FORCEPROP 2 LAST CDS_LIB pure_quanta
J 0
(-9650 3350);
DISPLAY INVISIBLE (-9650 3350);
FORCEPROP 1 LAST PATH I18
J 0
(-9700 3500);
DISPLAY 0.978723 (-9700 3500);
PAINT WHITE (-9700 3500);
DISPLAY INVISIBLE (-9700 3500);
FORCEPROP 0 LAST $SEC 1
J 0
(-9525 3425);
DISPLAY 0.680851 (-9525 3425);
PAINT MONO (-9525 3425);
DISPLAY INVISIBLE (-9525 3425);
FORCEPROP 0 LAST CDS_SEC 1
J 0
(-9525 3425);
DISPLAY 1.021277 (-9525 3425);
DISPLAY INVISIBLE (-9525 3425);
FORCEADD RS53318LR..1
(-8625 3450);
FORCEPROP 1 LAST PART_NUMBER AL053318002
J 0
(-8875 4275);
DISPLAY 0.723404 (-8875 4275);
PAINT GREEN (-8875 4275);
DISPLAY INVISIBLE (-8875 4275);
FORCEPROP 1 LAST MATERIAL IC
J 0
(-8870 4207);
DISPLAY 0.723404 (-8870 4207);
PAINT GREEN (-8870 4207);
FORCEPROP 2 LAST VALUE RS53318LR
J 0
(-8875 4350);
DISPLAY 0.617021 (-8875 4350);
PAINT SKYBLUE (-8875 4350);
FORCEPROP 2 LAST PART_TYPE SMLF
J 0
(-8875 4400);
DISPLAY 0.808511 (-8875 4400);
FORCEPROP 1 LAST LOCATION PU79
J 0
(-8870 4481);
DISPLAY 0.723404 (-8870 4481);
PAINT GREEN (-8870 4481);
FORCEPROP 2 LASTPIN (-8225 2775) $PN 2
J 0
(-8215 2785);
DISPLAY 0.680851 (-8215 2785);
PAINT MONO (-8215 2785);
FORCEPROP 2 LASTPIN (-8225 3925) $PN 1
J 0
(-8215 3935);
DISPLAY 0.680851 (-8215 3935);
PAINT MONO (-8215 3935);
FORCEPROP 2 LASTPIN (-9025 2825) $PN 3
J 2
(-9035 2835);
DISPLAY 0.680851 (-9035 2835);
PAINT MONO (-9035 2835);
FORCEPROP 2 LASTPIN (-9025 3625) $PN 8
J 2
(-9035 3635);
DISPLAY 0.680851 (-9035 3635);
PAINT MONO (-9035 3635);
FORCEPROP 2 LASTPIN (-8225 3175) $PN 7
J 0
(-8215 3185);
DISPLAY 0.680851 (-8215 3185);
PAINT MONO (-8215 3185);
FORCEPROP 2 LASTPIN (-9025 3425) $PN 4
J 2
(-9035 3435);
DISPLAY 0.680851 (-9035 3435);
PAINT MONO (-9035 3435);
FORCEPROP 2 LASTPIN (-8225 2825) $PN 11_18
J 0
(-8215 2835);
DISPLAY 0.680851 (-8215 2835);
PAINT MONO (-8215 2835);
FORCEPROP 2 LASTPIN (-8225 4125) $PN 9
J 0
(-8215 4135);
DISPLAY 0.680851 (-8215 4135);
PAINT MONO (-8215 4135);
FORCEPROP 2 LASTPIN (-8225 2925) $PN 5
J 0
(-8215 2935);
DISPLAY 0.680851 (-8215 2935);
PAINT MONO (-8215 2935);
FORCEPROP 2 LASTPIN (-8225 3025) $PN 6
J 0
(-8215 3035);
DISPLAY 0.680851 (-8215 3035);
PAINT MONO (-8215 3035);
FORCEPROP 2 LASTPIN (-8225 3625) $PN 20
J 0
(-8215 3635);
DISPLAY 0.680851 (-8215 3635);
PAINT MONO (-8215 3635);
FORCEPROP 2 LASTPIN (-9025 3175) $PN 19
J 2
(-9035 3185);
DISPLAY 0.680851 (-9035 3185);
PAINT MONO (-9035 3185);
FORCEPROP 2 LASTPIN (-9025 4125) $PN 10
J 2
(-9035 4135);
DISPLAY 0.680851 (-9035 4135);
PAINT MONO (-9035 4135);
FORCEPROP 2 LASTPIN (-9025 4075) $PN 21
J 2
(-9035 4085);
DISPLAY 0.680851 (-9035 4085);
PAINT MONO (-9035 4085);
FORCEPROP 2 LAST SEC_TYPE 
J 0
(-8900 4725);
DISPLAY 1.021277 (-8900 4725);
DISPLAY INVISIBLE (-8900 4725);
FORCEPROP 2 LAST CDS_LIB pure_quanta
J 0
(-8625 3450);
DISPLAY INVISIBLE (-8625 3450);
FORCEPROP 1 LAST NEEDS_NO_SIZE TRUE
J 0
(-8625 3450);
DISPLAY 0.723404 (-8625 3450);
PAINT GREEN (-8625 3450);
DISPLAY INVISIBLE (-8625 3450);
FORCEPROP 1 LAST CDS_LMAN_SYM_OUTLINE -250,725,250,-725
J 0
(-8625 3450);
DISPLAY 0.468085 (-8625 3450);
PAINT GREEN (-8625 3450);
DISPLAY INVISIBLE (-8625 3450);
FORCEPROP 1 LAST PATH I19
J 0
(-8625 3450);
DISPLAY 0.723404 (-8625 3450);
PAINT GREEN (-8625 3450);
DISPLAY INVISIBLE (-8625 3450);
FORCEPROP 2 LAST SEC 1
J 0
(-8900 4725);
DISPLAY 0.680851 (-8900 4725);
PAINT MONO (-8900 4725);
DISPLAY INVISIBLE (-8900 4725);
FORCEADD OFFPAGE..4
R 2
(-11600 3625);
FORCEPROP 2 LASTPIN (-11550 3625) SIG_NAME FM_PVPP_HBM_CPU0_EN
J 0
(-9735 3635);
DISPLAY 0.617021 (-9735 3635);
FORCEPROP 2 LAST $XR0 214 
J 0
(-11852 3625);
DISPLAY 0.638298 (-11852 3625);
PAINT MONO (-11852 3625);
FORCEPROP 2 LAST CDS_LIB standard
J 0
(-11600 3625);
DISPLAY INVISIBLE (-11600 3625);
FORCEPROP 1 LAST OFFPAGE TRUE
J 2
(-11925 3500);
DISPLAY 0.872340 (-11925 3500);
PAINT GREEN (-11925 3500);
DISPLAY INVISIBLE (-11925 3500);
FORCEPROP 1 LAST COMMENT_BODY TRUE
J 2
(-11575 3525);
DISPLAY 0.872340 (-11575 3525);
PAINT GREEN (-11575 3525);
DISPLAY INVISIBLE (-11575 3525);
FORCEPROP 2 LAST PATH I2
J 0
(-11850 3675);
DISPLAY 1.021277 (-11850 3675);
DISPLAY INVISIBLE (-11850 3675);
FORCEADD UNIVERSAL_GND..1
(-9175 3275);
FORCEPROP 3 LASTPIN (-9175 3325) SIG_NAME GND\g
J 0
(-9165 3335);
DISPLAY 0.659574 (-9165 3335);
PAINT MONO (-9165 3335);
DISPLAY INVISIBLE (-9165 3335);
FORCEPROP 2 LAST CDS_LIB logical_power
J 0
(-9175 3275);
DISPLAY INVISIBLE (-9175 3275);
FORCEPROP 1 LAST HDL_POWER GND
J 1
(-9150 3200);
DISPLAY 0.872340 (-9150 3200);
PAINT GREEN (-9150 3200);
DISPLAY INVISIBLE (-9150 3200);
FORCEPROP 1 LAST PATH I20
J 0
(-9100 3275);
DISPLAY 0.872340 (-9100 3275);
PAINT AQUA (-9100 3275);
DISPLAY INVISIBLE (-9100 3275);
FORCEADD VCCAUX15..1
(-11425 4800);
FORCEPROP 3 LASTPIN (-11425 4750) SIG_NAME SW_P12V_PVCCIN_CPU0_FLT\g
J 0
(-11415 4760);
DISPLAY 0.659574 (-11415 4760);
PAINT MONO (-11415 4760);
DISPLAY INVISIBLE (-11415 4760);
FORCEPROP 1 LAST HDL_POWER SW_P12V_PVCCIN_CPU0_FLT
J 1
(-11425 4842);
DISPLAY 0.617021 (-11425 4842);
PAINT GREEN (-11425 4842);
FORCEPROP 2 LAST BOM_COST VR_PCH
J 0
(-11425 4875);
DISPLAY 0.680851 (-11425 4875);
DISPLAY INVISIBLE (-11425 4875);
FORCEPROP 2 LAST CDS_LIB logical_power
J 0
(-11425 4800);
DISPLAY INVISIBLE (-11425 4800);
FORCEPROP 1 LAST PATH I21
J 0
(-11375 4825);
DISPLAY 0.872340 (-11375 4825);
PAINT AQUA (-11375 4825);
DISPLAY INVISIBLE (-11375 4825);
FORCEADD UNIVERSAL_GND..1
(-8125 2475);
FORCEPROP 3 LASTPIN (-8125 2525) SIG_NAME GND\g
J 0
(-8115 2535);
DISPLAY 0.659574 (-8115 2535);
PAINT MONO (-8115 2535);
DISPLAY INVISIBLE (-8115 2535);
FORCEPROP 2 LAST CDS_LIB logical_power
J 0
(-8125 2475);
DISPLAY INVISIBLE (-8125 2475);
FORCEPROP 1 LAST HDL_POWER GND
J 1
(-8100 2400);
DISPLAY 0.872340 (-8100 2400);
PAINT GREEN (-8100 2400);
DISPLAY INVISIBLE (-8100 2400);
FORCEPROP 1 LAST PATH I22
J 0
(-8050 2475);
DISPLAY 0.872340 (-8050 2475);
PAINT AQUA (-8050 2475);
DISPLAY INVISIBLE (-8050 2475);
FORCEADD Q_CAP..1
(-8000 2575);
FORCEPROP 1 LAST PART_NUMBER TMP_QCH32203KB11
J 0
(-7950 2425);
DISPLAY 0.510638 (-7950 2425);
DISPLAY INVISIBLE (-7950 2425);
FORCEPROP 1 LAST MATERIAL X7R
J 0
(-7950 2475);
DISPLAY 0.638298 (-7950 2475);
PAINT RED (-7950 2475);
FORCEPROP 1 LAST TOLERANCE 10%
J 0
(-7950 2525);
DISPLAY 0.638298 (-7950 2525);
FORCEPROP 1 LAST VALUE 0.022UF
J 0
(-7950 2625);
DISPLAY 0.638298 (-7950 2625);
FORCEPROP 1 LAST PACK_TYPE 0402
J 0
(-7950 2375);
DISPLAY 0.638298 (-7950 2375);
FORCEPROP 1 LAST VOLTAGE 16V
J 0
(-7950 2575);
DISPLAY 0.638298 (-7950 2575);
FORCEPROP 1 LAST LOCATION PC2001
J 0
(-7950 2675);
DISPLAY 0.978723 (-7950 2675);
FORCEPROP 2 LAST CDS_LIB pure_quanta
J 0
(-8000 2575);
DISPLAY INVISIBLE (-8000 2575);
FORCEPROP 1 LAST PATH I23
J 0
(-7950 2725);
DISPLAY 0.978723 (-7950 2725);
PAINT WHITE (-7950 2725);
DISPLAY INVISIBLE (-7950 2725);
FORCEPROP 0 LAST $SEC 1
J 0
(-7950 2725);
DISPLAY INVISIBLE (-7950 2725);
FORCEPROP 0 LAST CDS_SEC 1
J 0
(-7950 2725);
DISPLAY INVISIBLE (-7950 2725);
FORCEPROP 1 LASTPIN (-8000 2675) $PN 1
J 0
(-7990 2655);
DISPLAY 0.787234 (-7990 2655);
PAINT MONO (-7990 2655);
DISPLAY INVISIBLE (-7990 2655);
FORCEPROP 1 LASTPIN (-8000 2475) $PN 2
J 0
(-7990 2455);
DISPLAY 0.787234 (-7990 2455);
PAINT MONO (-7990 2455);
DISPLAY INVISIBLE (-7990 2455);
FORCEADD UNIVERSAL_GND..1
(-8000 2325);
FORCEPROP 3 LASTPIN (-8000 2375) SIG_NAME GND\g
J 0
(-7990 2385);
DISPLAY 0.659574 (-7990 2385);
PAINT MONO (-7990 2385);
DISPLAY INVISIBLE (-7990 2385);
FORCEPROP 2 LAST CDS_LIB logical_power
J 0
(-8000 2325);
DISPLAY INVISIBLE (-8000 2325);
FORCEPROP 1 LAST HDL_POWER GND
J 1
(-7975 2250);
DISPLAY 0.872340 (-7975 2250);
PAINT GREEN (-7975 2250);
DISPLAY INVISIBLE (-7975 2250);
FORCEPROP 1 LAST PATH I24
J 0
(-7925 2325);
DISPLAY 0.872340 (-7925 2325);
PAINT AQUA (-7925 2325);
DISPLAY INVISIBLE (-7925 2325);
FORCEADD Q_CAP..1
(-7500 2475);
FORCEPROP 1 LAST PART_NUMBER CH4104K1B00
J 0
(-7450 2325);
DISPLAY 0.617021 (-7450 2325);
PAINT BLUE (-7450 2325);
DISPLAY INVISIBLE (-7450 2325);
FORCEPROP 1 LAST VALUE 0.1UF
J 0
(-7450 2525);
DISPLAY 0.617021 (-7450 2525);
PAINT SKYBLUE (-7450 2525);
FORCEPROP 1 LAST VOLTAGE 25V
J 0
(-7450 2475);
DISPLAY 0.617021 (-7450 2475);
PAINT SKYBLUE (-7450 2475);
FORCEPROP 1 LAST MATERIAL X7R
J 0
(-7450 2375);
DISPLAY 0.617021 (-7450 2375);
PAINT RED (-7450 2375);
FORCEPROP 1 LAST PACK_TYPE 0402
J 0
(-7450 2275);
DISPLAY 0.617021 (-7450 2275);
PAINT SKYBLUE (-7450 2275);
FORCEPROP 1 LAST TOLERANCE 10%
J 0
(-7450 2425);
DISPLAY 0.617021 (-7450 2425);
PAINT SKYBLUE (-7450 2425);
FORCEPROP 1 LAST LOCATION PC1251
J 0
(-7450 2575);
DISPLAY 0.617021 (-7450 2575);
PAINT AQUA (-7450 2575);
FORCEPROP 1 LASTPIN (-7500 2575) $PN 1
J 0
(-7490 2555);
DISPLAY 0.617021 (-7490 2555);
PAINT MONO (-7490 2555);
FORCEPROP 1 LASTPIN (-7500 2375) $PN 2
J 0
(-7490 2355);
DISPLAY 0.617021 (-7490 2355);
PAINT MONO (-7490 2355);
FORCEPROP 2 LAST CDS_LIB pure_quanta
J 0
(-7500 2475);
DISPLAY INVISIBLE (-7500 2475);
FORCEPROP 1 LAST PATH I25
J 0
(-7450 2625);
DISPLAY 0.978723 (-7450 2625);
PAINT WHITE (-7450 2625);
DISPLAY INVISIBLE (-7450 2625);
FORCEPROP 2 LAST $SEC 1
J 0
(-7450 2675);
DISPLAY 0.680851 (-7450 2675);
PAINT MONO (-7450 2675);
DISPLAY INVISIBLE (-7450 2675);
FORCEPROP 2 LAST CDS_SEC 1
J 0
(-7450 2675);
DISPLAY 1.021277 (-7450 2675);
DISPLAY INVISIBLE (-7450 2675);
FORCEADD Q_RES..2
(-7000 2450);
FORCEPROP 1 LAST PART_NUMBER CS31132BB02
J 0
(-6960 2325);
DISPLAY 0.510638 (-6960 2325);
DISPLAY INVISIBLE (-6960 2325);
FORCEPROP 1 LAST VALUE 11.3K
J 0
(-6955 2525);
DISPLAY 0.510638 (-6955 2525);
FORCEPROP 1 LAST PACK_TYPE 0402LF
J 0
(-6960 2275);
DISPLAY 0.510638 (-6960 2275);
FORCEPROP 1 LAST MATERIAL CHIP
J 0
(-6960 2375);
DISPLAY 0.510638 (-6960 2375);
FORCEPROP 1 LAST WATTAGE 1/16W
J 0
(-6960 2425);
DISPLAY 0.510638 (-6960 2425);
FORCEPROP 1 LAST TOLERANCE 0.1%
J 0
(-6955 2475);
DISPLAY 0.510638 (-6955 2475);
FORCEPROP 1 LAST LOCATION PR1310
J 0
(-6955 2575);
DISPLAY 0.510638 (-6955 2575);
FORCEPROP 1 LASTPIN (-7000 2550) $PN 1
J 0
(-6995 2512);
DISPLAY 0.787234 (-6995 2512);
PAINT MONO (-6995 2512);
FORCEPROP 1 LASTPIN (-7000 2350) $PN 2
J 0
(-6995 2360);
DISPLAY 0.787234 (-6995 2360);
PAINT MONO (-6995 2360);
FORCEPROP 2 LAST CDS_LIB pure_quanta
J 0
(-7000 2450);
DISPLAY INVISIBLE (-7000 2450);
FORCEPROP 2 LAST BOM_COST VR_PCH
J 0
(-6950 2625);
DISPLAY 0.680851 (-6950 2625);
DISPLAY INVISIBLE (-6950 2625);
FORCEPROP 1 LAST PATH I26
J 0
(-6950 2625);
DISPLAY 0.978723 (-6950 2625);
PAINT WHITE (-6950 2625);
DISPLAY INVISIBLE (-6950 2625);
FORCEPROP 0 LAST $SEC 1
J 0
(-6950 2600);
DISPLAY 0.680851 (-6950 2600);
PAINT MONO (-6950 2600);
DISPLAY INVISIBLE (-6950 2600);
FORCEPROP 2 LAST CDS_SEC 1
J 0
(-6950 2675);
DISPLAY 0.680851 (-6950 2675);
DISPLAY INVISIBLE (-6950 2675);
FORCEADD Q_CAP..1
(-7350 3850);
FORCEPROP 1 LAST PART_NUMBER CH4224K1B01
J 0
(-7300 3700);
DISPLAY 0.617021 (-7300 3700);
PAINT BLUE (-7300 3700);
DISPLAY INVISIBLE (-7300 3700);
FORCEPROP 1 LAST VOLTAGE 25V
J 0
(-7300 3850);
DISPLAY 0.617021 (-7300 3850);
PAINT SKYBLUE (-7300 3850);
FORCEPROP 1 LAST MATERIAL X7R
J 0
(-7300 3750);
DISPLAY 0.617021 (-7300 3750);
PAINT RED (-7300 3750);
FORCEPROP 1 LAST TOLERANCE 10%
J 0
(-7300 3800);
DISPLAY 0.617021 (-7300 3800);
PAINT SKYBLUE (-7300 3800);
FORCEPROP 1 LAST VALUE 0.22UF
J 0
(-7300 3900);
DISPLAY 0.617021 (-7300 3900);
PAINT SKYBLUE (-7300 3900);
FORCEPROP 1 LAST PACK_TYPE C0402
J 0
(-7300 3650);
DISPLAY 0.617021 (-7300 3650);
PAINT SKYBLUE (-7300 3650);
FORCEPROP 1 LAST LOCATION PC1252
J 0
(-7300 3950);
DISPLAY 0.617021 (-7300 3950);
PAINT AQUA (-7300 3950);
FORCEPROP 1 LASTPIN (-7350 3950) $PN 1
J 0
(-7340 3930);
DISPLAY 0.617021 (-7340 3930);
PAINT MONO (-7340 3930);
FORCEPROP 1 LASTPIN (-7350 3750) $PN 2
J 0
(-7340 3730);
DISPLAY 0.617021 (-7340 3730);
PAINT MONO (-7340 3730);
FORCEPROP 2 LAST CDS_LIB pure_quanta
J 0
(-7350 3850);
DISPLAY INVISIBLE (-7350 3850);
FORCEPROP 1 LAST PATH I27
J 0
(-7300 4000);
DISPLAY 0.978723 (-7300 4000);
PAINT WHITE (-7300 4000);
DISPLAY INVISIBLE (-7300 4000);
FORCEPROP 2 LAST $SEC 1
J 0
(-7300 4050);
DISPLAY 0.680851 (-7300 4050);
PAINT MONO (-7300 4050);
DISPLAY INVISIBLE (-7300 4050);
FORCEPROP 2 LAST CDS_SEC 1
J 0
(-7300 4050);
DISPLAY 1.021277 (-7300 4050);
DISPLAY INVISIBLE (-7300 4050);
FORCEADD Q_INDUCTOR..1
(-6525 3650);
FORCEPROP 1 LAST PART_NUMBER CV+68F5MZ05
J 0
(-6650 3760);
DISPLAY 0.617021 (-6650 3760);
PAINT BLUE (-6650 3760);
DISPLAY INVISIBLE (-6650 3760);
FORCEPROP 2 LAST PACK_TYPE SMLF
J 0
(-6650 3875);
DISPLAY 0.617021 (-6650 3875);
PAINT SKYBLUE (-6650 3875);
FORCEPROP 1 LAST MATERIAL IND
J 0
(-6650 3705);
DISPLAY 0.617021 (-6650 3705);
PAINT RED (-6650 3705);
FORCEPROP 2 LAST VALUE 0.68UH
J 0
(-6650 3825);
DISPLAY 0.617021 (-6650 3825);
PAINT SKYBLUE (-6650 3825);
FORCEPROP 1 LAST LOCATION PL118
J 0
(-6825 3635);
DISPLAY 0.617021 (-6825 3635);
PAINT AQUA (-6825 3635);
FORCEPROP 2 LASTPIN (-6625 3625) $PN 1
J 2
(-6635 3635);
DISPLAY 0.617021 (-6635 3635);
FORCEPROP 2 LASTPIN (-6425 3625) $PN 2
J 0
(-6415 3635);
DISPLAY 0.617021 (-6415 3635);
FORCEPROP 2 LAST BOM_COST VR_PCH
J 0
(-6650 3950);
DISPLAY 0.680851 (-6650 3950);
DISPLAY INVISIBLE (-6650 3950);
FORCEPROP 1 LAST NEEDS_NO_SIZE TRUE
J 0
(-6525 3650);
DISPLAY 0.468085 (-6525 3650);
PAINT GREEN (-6525 3650);
DISPLAY INVISIBLE (-6525 3650);
FORCEPROP 2 LAST CDS_LIB pure_quanta
J 0
(-6525 3650);
PAINT MONO (-6525 3650);
DISPLAY INVISIBLE (-6525 3650);
FORCEPROP 1 LAST PATH I28
J 0
(-6450 3705);
DISPLAY 0.723404 (-6450 3705);
PAINT GREEN (-6450 3705);
DISPLAY INVISIBLE (-6450 3705);
FORCEPROP 2 LAST $SEC 1
J 0
(-6650 3925);
DISPLAY 0.680851 (-6650 3925);
PAINT MONO (-6650 3925);
DISPLAY INVISIBLE (-6650 3925);
FORCEPROP 2 LAST CDS_SEC 1
J 0
(-6650 3925);
DISPLAY 1.021277 (-6650 3925);
DISPLAY INVISIBLE (-6650 3925);
FORCEADD Q_RES..1
(-6800 4325);
FORCEPROP 1 LAST PART_NUMBER CS00002JB13
J 0
(-6850 4375);
DISPLAY 0.617021 (-6850 4375);
PAINT BLUE (-6850 4375);
DISPLAY INVISIBLE (-6850 4375);
FORCEPROP 1 LAST VALUE 0
J 2
(-6650 4325);
DISPLAY 0.617021 (-6650 4325);
PAINT SKYBLUE (-6650 4325);
FORCEPROP 1 LAST MATERIAL CHIP
J 0
(-6850 4400);
DISPLAY 0.617021 (-6850 4400);
PAINT RED (-6850 4400);
FORCEPROP 1 LAST WATTAGE 1/16W
J 2
(-6550 4400);
DISPLAY 0.617021 (-6550 4400);
PAINT SKYBLUE (-6550 4400);
FORCEPROP 1 LAST PACK_TYPE 0402LF
J 0
(-6850 4425);
DISPLAY 0.617021 (-6850 4425);
PAINT SKYBLUE (-6850 4425);
FORCEPROP 1 LAST TOLERANCE 5%
J 0
(-6625 4325);
DISPLAY 0.617021 (-6625 4325);
PAINT SKYBLUE (-6625 4325);
FORCEPROP 1 LAST LOCATION R2408
J 0
(-7075 4325);
DISPLAY 0.723404 (-7075 4325);
PAINT AQUA (-7075 4325);
FORCEPROP 1 LASTPIN (-6900 4325) $PN 1
J 0
(-6888 4337);
DISPLAY 0.617021 (-6888 4337);
FORCEPROP 1 LASTPIN (-6700 4325) $PN 2
J 0
(-6738 4337);
DISPLAY 0.617021 (-6738 4337);
FORCEPROP 2 LAST CDS_LIB pure_quanta
J 0
(-6800 4325);
PAINT MONO (-6800 4325);
DISPLAY INVISIBLE (-6800 4325);
FORCEPROP 1 LAST PATH I29
J 0
(-6850 4475);
DISPLAY 0.978723 (-6850 4475);
PAINT WHITE (-6850 4475);
DISPLAY INVISIBLE (-6850 4475);
FORCEPROP 2 LAST $SEC 1
J 0
(-6850 4525);
DISPLAY 0.680851 (-6850 4525);
PAINT MONO (-6850 4525);
DISPLAY INVISIBLE (-6850 4525);
FORCEPROP 2 LAST CDS_SEC 1
J 0
(-6850 4525);
DISPLAY 1.021277 (-6850 4525);
DISPLAY INVISIBLE (-6850 4525);
FORCEADD VCCAUX15..1
(-11750 3875);
FORCEPROP 3 LASTPIN (-11750 3825) SIG_NAME P3V3_AUX\g
J 0
(-11740 3835);
DISPLAY 0.659574 (-11740 3835);
PAINT MONO (-11740 3835);
DISPLAY INVISIBLE (-11740 3835);
FORCEPROP 1 LAST HDL_POWER P3V3_AUX
J 1
(-11750 3917);
DISPLAY 0.617021 (-11750 3917);
PAINT GREEN (-11750 3917);
FORCEPROP 2 LAST CDS_LIB logical_power
J 0
(-11750 3875);
PAINT MONO (-11750 3875);
DISPLAY INVISIBLE (-11750 3875);
FORCEPROP 2 LAST BOM_COST VR_PCH
J 0
(-11750 3950);
DISPLAY 0.680851 (-11750 3950);
DISPLAY INVISIBLE (-11750 3950);
FORCEPROP 1 LAST PATH I3
J 0
(-11700 3900);
DISPLAY 0.872340 (-11700 3900);
PAINT AQUA (-11700 3900);
DISPLAY INVISIBLE (-11700 3900);
FORCEADD Q_CAP..2
(-6800 4200);
FORCEPROP 1 LAST PART_NUMBER TMP_QCH21006JB10
J 1
(-6775 4125);
DISPLAY 0.617021 (-6775 4125);
PAINT BLUE (-6775 4125);
DISPLAY INVISIBLE (-6775 4125);
FORCEPROP 1 LAST PACK_TYPE 0402
J 1
(-6750 4075);
DISPLAY 0.617021 (-6750 4075);
PAINT SKYBLUE (-6750 4075);
FORCEPROP 1 LAST VOLTAGE 50V
J 0
(-6525 4200);
DISPLAY 0.617021 (-6525 4200);
PAINT SKYBLUE (-6525 4200);
FORCEPROP 1 LAST MATERIAL X7R
J 0
(-6975 4075);
DISPLAY 0.617021 (-6975 4075);
PAINT RED (-6975 4075);
FORCEPROP 1 LAST VALUE 1000PF
J 2
(-6550 4200);
DISPLAY 0.617021 (-6550 4200);
PAINT SKYBLUE (-6550 4200);
FORCEPROP 1 LAST TOLERANCE 5%
J 2
(-6825 4075);
DISPLAY 0.617021 (-6825 4075);
PAINT SKYBLUE (-6825 4075);
FORCEPROP 1 LAST LOCATION C1301
J 1
(-6975 4200);
DISPLAY 0.723404 (-6975 4200);
PAINT AQUA (-6975 4200);
FORCEPROP 1 LASTPIN (-6900 4200) $PN 1
J 0
(-6910 4215);
DISPLAY 0.617021 (-6910 4215);
FORCEPROP 1 LASTPIN (-6700 4200) $PN 2
J 0
(-6715 4215);
DISPLAY 0.617021 (-6715 4215);
FORCEPROP 2 LAST CDS_LIB pure_quanta
J 0
(-6800 4200);
PAINT MONO (-6800 4200);
DISPLAY INVISIBLE (-6800 4200);
FORCEPROP 1 LAST PATH I30
J 0
(-6800 4400);
DISPLAY 0.978723 (-6800 4400);
PAINT WHITE (-6800 4400);
DISPLAY INVISIBLE (-6800 4400);
FORCEPROP 2 LAST $SEC 1
J 0
(-6800 4450);
DISPLAY 0.680851 (-6800 4450);
PAINT MONO (-6800 4450);
DISPLAY INVISIBLE (-6800 4450);
FORCEPROP 2 LAST CDS_SEC 1
J 0
(-6800 4450);
DISPLAY 1.021277 (-6800 4450);
DISPLAY INVISIBLE (-6800 4450);
FORCEADD MOSFET_N..1
R 2
(-6275 2225);
FORCEPROP 1 LAST PART_NUMBER BAM138K0000
J 2
(-6422 2136);
DISPLAY 0.617021 (-6422 2136);
PAINT BLUE (-6422 2136);
DISPLAY INVISIBLE (-6422 2136);
FORCEPROP 1 LAST MATERIAL EMPTY
J 2
(-6422 2056);
DISPLAY 0.617021 (-6422 2056);
PAINT RED (-6422 2056);
FORCEPROP 1 LAST VALUE BSS138K
J 2
(-6422 2296);
DISPLAY 0.617021 (-6422 2296);
PAINT SKYBLUE (-6422 2296);
FORCEPROP 2 LAST PATH I31
J 0
(-6400 2325);
DISPLAY 1.021277 (-6400 2325);
FORCEPROP 1 LAST LOCATION PU173
J 2
(-6422 2216);
DISPLAY 0.723404 (-6422 2216);
PAINT AQUA (-6422 2216);
FORCEPROP 1 LASTPIN (-6325 2325) $PN D
R 1
J 0
(-6325 2318);
DISPLAY 0.617021 (-6325 2318);
PAINT GREEN (-6325 2318);
FORCEPROP 1 LASTPIN (-6175 2125) $PN G
J 0
(-6185 2128);
DISPLAY 0.617021 (-6185 2128);
PAINT GREEN (-6185 2128);
FORCEPROP 1 LASTPIN (-6325 2025) $PN S
R 1
J 2
(-6325 2038);
DISPLAY 0.617021 (-6325 2038);
PAINT GREEN (-6325 2038);
FORCEPROP 1 LAST PACK_TYPE SMLF
J 2
(-6300 1975);
DISPLAY 0.723404 (-6300 1975);
PAINT SKYBLUE (-6300 1975);
DISPLAY INVISIBLE (-6300 1975);
FORCEPROP 2 LAST CDS_LIB pure_quanta
J 2
(-6275 2225);
PAINT MONO (-6275 2225);
DISPLAY INVISIBLE (-6275 2225);
FORCEPROP 1 LAST CDS_LMAN_SYM_OUTLINE -50,50,100,-150
J 2
(-6275 2225);
DISPLAY 0.468085 (-6275 2225);
PAINT GREEN (-6275 2225);
DISPLAY INVISIBLE (-6275 2225);
FORCEPROP 0 LAST MANUF_PN BSS138K
J 2
(-6450 2100);
DISPLAY 0.808511 (-6450 2100);
DISPLAY INVISIBLE (-6450 2100);
FORCEPROP 2 LAST $SEC 1
J 0
(-6425 2375);
DISPLAY 0.680851 (-6425 2375);
PAINT MONO (-6425 2375);
DISPLAY INVISIBLE (-6425 2375);
FORCEPROP 2 LAST CDS_SEC 1
J 0
(-6425 2375);
DISPLAY 1.021277 (-6425 2375);
DISPLAY INVISIBLE (-6425 2375);
FORCEADD OFFPAGE..4
(-5500 2125);
FORCEPROP 2 LAST $XR1 299 
J 0
(-5194 2125);
DISPLAY 0.638298 (-5194 2125);
PAINT MONO (-5194 2125);
FORCEPROP 2 LAST $XR0 215 
J 0
(-5314 2125);
DISPLAY 0.638298 (-5314 2125);
PAINT MONO (-5314 2125);
FORCEPROP 2 LAST CDS_LIB standard
J 0
(-5500 2125);
PAINT MONO (-5500 2125);
DISPLAY INVISIBLE (-5500 2125);
FORCEPROP 1 LAST OFFPAGE TRUE
J 0
(-5175 2000);
DISPLAY 0.872340 (-5175 2000);
PAINT GREEN (-5175 2000);
DISPLAY INVISIBLE (-5175 2000);
FORCEPROP 1 LAST COMMENT_BODY TRUE
J 0
(-5525 2025);
DISPLAY 0.872340 (-5525 2025);
PAINT GREEN (-5525 2025);
DISPLAY INVISIBLE (-5525 2025);
FORCEPROP 2 LAST PATH I32
J 0
(-5175 2175);
DISPLAY 1.021277 (-5175 2175);
DISPLAY INVISIBLE (-5175 2175);
FORCEADD Q_SHORT..1
(-4600 1900);
FORCEPROP 1 LAST PART_NUMBER SHORT6
J 0
(-4675 2010);
DISPLAY 0.617021 (-4675 2010);
PAINT BLUE (-4675 2010);
DISPLAY INVISIBLE (-4675 2010);
FORCEPROP 1 LAST MATERIAL EMPTY
J 0
(-4675 2060);
DISPLAY 0.617021 (-4675 2060);
PAINT RED (-4675 2060);
FORCEPROP 2 LAST PACK_TYPE SM
J 0
(-4675 2100);
DISPLAY 0.617021 (-4675 2100);
PAINT SKYBLUE (-4675 2100);
FORCEPROP 1 LAST LOCATION PJ65
J 0
(-4675 1955);
DISPLAY 0.617021 (-4675 1955);
PAINT AQUA (-4675 1955);
FORCEPROP 0 LASTPIN (-4725 1900) $PN 1
J 2
(-4735 1910);
DISPLAY 0.808511 (-4735 1910);
FORCEPROP 0 LASTPIN (-4475 1900) $PN 2
J 0
(-4465 1910);
DISPLAY 0.808511 (-4465 1910);
FORCEPROP 2 LAST CDS_LIB pure_quanta
J 0
(-4600 1900);
DISPLAY INVISIBLE (-4600 1900);
FORCEPROP 1 LAST NEEDS_NO_SIZE TRUE
J 0
(-4600 1900);
DISPLAY 0.468085 (-4600 1900);
PAINT GREEN (-4600 1900);
DISPLAY INVISIBLE (-4600 1900);
FORCEPROP 2 LAST BOM_COST VR_PCH
J 0
(-4675 2150);
DISPLAY 0.680851 (-4675 2150);
DISPLAY INVISIBLE (-4675 2150);
FORCEPROP 1 LAST PATH I33
J 0
(-4675 2105);
DISPLAY 0.723404 (-4675 2105);
PAINT GREEN (-4675 2105);
DISPLAY INVISIBLE (-4675 2105);
FORCEPROP 0 LAST $SEC 1
J 0
(-4675 2150);
DISPLAY INVISIBLE (-4675 2150);
FORCEPROP 0 LAST CDS_SEC 1
J 0
(-4675 2150);
DISPLAY INVISIBLE (-4675 2150);
FORCEADD Q_RES..1
(-6350 2475);
FORCEPROP 1 LAST PART_NUMBER CS32612BB02
J 0
(-6525 2525);
DISPLAY 0.617021 (-6525 2525);
PAINT BLUE (-6525 2525);
DISPLAY INVISIBLE (-6525 2525);
FORCEPROP 1 LAST WATTAGE 1/16W
J 2
(-6025 2575);
DISPLAY 0.617021 (-6025 2575);
PAINT SKYBLUE (-6025 2575);
FORCEPROP 1 LAST PACK_TYPE 0402LF
J 0
(-6375 2575);
DISPLAY 0.617021 (-6375 2575);
PAINT SKYBLUE (-6375 2575);
FORCEPROP 1 LAST TOLERANCE 0.1%
J 0
(-6000 2500);
DISPLAY 0.617021 (-6000 2500);
PAINT SKYBLUE (-6000 2500);
FORCEPROP 1 LAST VALUE 26.1K
J 2
(-6050 2500);
DISPLAY 0.617021 (-6050 2500);
PAINT SKYBLUE (-6050 2500);
FORCEPROP 1 LAST MATERIAL EMPTY
J 0
(-6525 2575);
DISPLAY 0.617021 (-6525 2575);
PAINT RED (-6525 2575);
FORCEPROP 1 LAST LOCATION PR2336
J 0
(-6625 2475);
DISPLAY 0.574468 (-6625 2475);
PAINT AQUA (-6625 2475);
FORCEPROP 1 LASTPIN (-6450 2475) $PN 1
J 0
(-6438 2487);
DISPLAY 0.617021 (-6438 2487);
FORCEPROP 1 LASTPIN (-6250 2475) $PN 2
J 0
(-6288 2487);
DISPLAY 0.617021 (-6288 2487);
FORCEPROP 2 LAST CDS_LIB pure_quanta
J 0
(-6350 2475);
PAINT MONO (-6350 2475);
DISPLAY INVISIBLE (-6350 2475);
FORCEPROP 1 LAST PATH I34
J 0
(-6400 2625);
DISPLAY 0.978723 (-6400 2625);
PAINT WHITE (-6400 2625);
DISPLAY INVISIBLE (-6400 2625);
FORCEPROP 2 LAST $SEC 1
J 0
(-6400 2675);
DISPLAY 0.680851 (-6400 2675);
PAINT MONO (-6400 2675);
DISPLAY INVISIBLE (-6400 2675);
FORCEPROP 2 LAST CDS_SEC 1
J 0
(-6400 2675);
DISPLAY 1.021277 (-6400 2675);
DISPLAY INVISIBLE (-6400 2675);
FORCEADD Q_CAP..2
(-6350 2700);
FORCEPROP 1 LAST PART_NUMBER CH1686K1B09
J 1
(-6350 2775);
DISPLAY 0.617021 (-6350 2775);
PAINT BLUE (-6350 2775);
DISPLAY INVISIBLE (-6350 2775);
FORCEPROP 1 LAST VALUE 680PF
J 2
(-6075 2700);
DISPLAY 0.617021 (-6075 2700);
PAINT SKYBLUE (-6075 2700);
FORCEPROP 1 LAST TOLERANCE 10%
J 2
(-5975 2700);
DISPLAY 0.617021 (-5975 2700);
PAINT SKYBLUE (-5975 2700);
FORCEPROP 1 LAST VOLTAGE 50V
J 0
(-6225 2825);
DISPLAY 0.617021 (-6225 2825);
PAINT SKYBLUE (-6225 2825);
FORCEPROP 1 LAST MATERIAL X7R
J 0
(-6525 2825);
DISPLAY 0.617021 (-6525 2825);
PAINT RED (-6525 2825);
FORCEPROP 1 LAST PACK_TYPE C0402
J 1
(-6325 2825);
DISPLAY 0.617021 (-6325 2825);
PAINT SKYBLUE (-6325 2825);
FORCEPROP 1 LAST LOCATION PC1253
J 1
(-6550 2700);
DISPLAY 0.617021 (-6550 2700);
PAINT AQUA (-6550 2700);
FORCEPROP 1 LASTPIN (-6450 2700) $PN 1
J 0
(-6460 2715);
DISPLAY 0.617021 (-6460 2715);
PAINT MONO (-6460 2715);
FORCEPROP 1 LASTPIN (-6250 2700) $PN 2
J 0
(-6265 2715);
DISPLAY 0.617021 (-6265 2715);
PAINT MONO (-6265 2715);
FORCEPROP 2 LAST CDS_LIB pure_quanta
J 0
(-6350 2700);
DISPLAY INVISIBLE (-6350 2700);
FORCEPROP 1 LAST PATH I35
J 0
(-6350 2900);
DISPLAY 0.978723 (-6350 2900);
PAINT WHITE (-6350 2900);
DISPLAY INVISIBLE (-6350 2900);
FORCEPROP 2 LAST $SEC 1
J 0
(-6350 2950);
DISPLAY 0.680851 (-6350 2950);
PAINT MONO (-6350 2950);
DISPLAY INVISIBLE (-6350 2950);
FORCEPROP 2 LAST CDS_SEC 1
J 0
(-6350 2950);
DISPLAY 1.021277 (-6350 2950);
DISPLAY INVISIBLE (-6350 2950);
FORCEADD Q_RES..1
(-6400 2950);
FORCEPROP 1 LAST PART_NUMBER CS33832BB06
J 0
(-6600 3000);
DISPLAY 0.319149 (-6600 3000);
DISPLAY INVISIBLE (-6600 3000);
FORCEPROP 1 LAST TOLERANCE 0.1%
J 0
(-6450 2900);
DISPLAY 0.404255 (-6450 2900);
FORCEPROP 1 LAST VALUE 38.3K
J 2
(-6475 2900);
DISPLAY 0.404255 (-6475 2900);
FORCEPROP 1 LAST WATTAGE 1/16W
J 2
(-6475 2875);
DISPLAY 0.404255 (-6475 2875);
FORCEPROP 1 LAST MATERIAL CHIP
J 0
(-6450 2875);
DISPLAY 0.404255 (-6450 2875);
FORCEPROP 1 LAST PACK_TYPE 0402LF
J 0
(-6325 2900);
DISPLAY 0.404255 (-6325 2900);
FORCEPROP 1 LAST LOCATION PR1337
J 0
(-6600 2950);
DISPLAY 0.319149 (-6600 2950);
FORCEPROP 1 LASTPIN (-6500 2950) $PN 1
J 0
(-6488 2962);
DISPLAY 0.787234 (-6488 2962);
PAINT MONO (-6488 2962);
FORCEPROP 1 LASTPIN (-6300 2950) $PN 2
J 0
(-6338 2962);
DISPLAY 0.787234 (-6338 2962);
PAINT MONO (-6338 2962);
FORCEPROP 2 LAST CDS_LIB pure_quanta
J 0
(-6400 2950);
DISPLAY INVISIBLE (-6400 2950);
FORCEPROP 1 LAST PATH I36
J 0
(-6450 3100);
DISPLAY 0.978723 (-6450 3100);
PAINT WHITE (-6450 3100);
DISPLAY INVISIBLE (-6450 3100);
FORCEPROP 0 LAST $SEC 1
J 0
(-6600 3025);
DISPLAY 0.680851 (-6600 3025);
PAINT MONO (-6600 3025);
DISPLAY INVISIBLE (-6600 3025);
FORCEPROP 2 LAST CDS_SEC 1
J 0
(-6450 3150);
DISPLAY 1.021277 (-6450 3150);
DISPLAY INVISIBLE (-6450 3150);
FORCEADD UNIVERSAL_GND..1
(-6325 4100);
FORCEPROP 3 LASTPIN (-6325 4150) SIG_NAME GND\g
J 0
(-6315 4160);
DISPLAY 0.659574 (-6315 4160);
PAINT MONO (-6315 4160);
DISPLAY INVISIBLE (-6315 4160);
FORCEPROP 2 LAST CDS_LIB logical_power
J 0
(-6325 4100);
PAINT MONO (-6325 4100);
DISPLAY INVISIBLE (-6325 4100);
FORCEPROP 1 LAST HDL_POWER GND
J 1
(-6300 4025);
DISPLAY 0.872340 (-6300 4025);
PAINT GREEN (-6300 4025);
DISPLAY INVISIBLE (-6300 4025);
FORCEPROP 1 LAST PATH I37
J 0
(-6250 4100);
DISPLAY 0.872340 (-6250 4100);
PAINT AQUA (-6250 4100);
DISPLAY INVISIBLE (-6250 4100);
FORCEADD Q_CAP..1
(-5900 3425);
FORCEPROP 1 LAST PART_NUMBER CH4104K1B00
J 0
(-5850 3275);
DISPLAY 0.617021 (-5850 3275);
PAINT BLUE (-5850 3275);
DISPLAY INVISIBLE (-5850 3275);
FORCEPROP 1 LAST VALUE 0.1UF
J 0
(-5850 3475);
DISPLAY 0.617021 (-5850 3475);
PAINT SKYBLUE (-5850 3475);
FORCEPROP 1 LAST TOLERANCE 10%
J 0
(-5850 3375);
DISPLAY 0.617021 (-5850 3375);
PAINT SKYBLUE (-5850 3375);
FORCEPROP 1 LAST VOLTAGE 25V
J 0
(-5850 3425);
DISPLAY 0.617021 (-5850 3425);
PAINT SKYBLUE (-5850 3425);
FORCEPROP 1 LAST MATERIAL X7R
J 0
(-5850 3325);
DISPLAY 0.617021 (-5850 3325);
PAINT RED (-5850 3325);
FORCEPROP 1 LAST PACK_TYPE 0402
J 0
(-5850 3225);
DISPLAY 0.617021 (-5850 3225);
PAINT SKYBLUE (-5850 3225);
FORCEPROP 1 LAST LOCATION PC1254
J 0
(-5850 3525);
DISPLAY 0.617021 (-5850 3525);
PAINT AQUA (-5850 3525);
FORCEPROP 1 LASTPIN (-5900 3525) $PN 1
J 0
(-5890 3505);
DISPLAY 0.617021 (-5890 3505);
PAINT MONO (-5890 3505);
FORCEPROP 1 LASTPIN (-5900 3325) $PN 2
J 0
(-5890 3305);
DISPLAY 0.617021 (-5890 3305);
PAINT MONO (-5890 3305);
FORCEPROP 2 LAST CDS_LIB pure_quanta
J 0
(-5900 3425);
DISPLAY INVISIBLE (-5900 3425);
FORCEPROP 1 LAST PATH I38
J 0
(-5850 3575);
DISPLAY 0.978723 (-5850 3575);
PAINT WHITE (-5850 3575);
DISPLAY INVISIBLE (-5850 3575);
FORCEPROP 2 LAST $SEC 1
J 0
(-5850 3625);
DISPLAY 0.680851 (-5850 3625);
PAINT MONO (-5850 3625);
DISPLAY INVISIBLE (-5850 3625);
FORCEPROP 2 LAST CDS_SEC 1
J 0
(-5850 3625);
DISPLAY 1.021277 (-5850 3625);
DISPLAY INVISIBLE (-5850 3625);
FORCEADD OFFPAGE..2
(-5650 4325);
FORCEPROP 2 LAST $XR1 253 
J 0
(-5341 4325);
DISPLAY 0.638298 (-5341 4325);
PAINT MONO (-5341 4325);
FORCEPROP 2 LAST $XR0 213 
J 0
(-5461 4325);
DISPLAY 0.638298 (-5461 4325);
PAINT MONO (-5461 4325);
FORCEPROP 2 LAST CDS_LIB standard
J 0
(-5650 4325);
PAINT MONO (-5650 4325);
DISPLAY INVISIBLE (-5650 4325);
FORCEPROP 2 LAST BOM_COST VR_SYSTEM 
J 0
(-5300 4375);
DISPLAY 0.680851 (-5300 4375);
DISPLAY INVISIBLE (-5300 4375);
FORCEPROP 1 LAST OFFPAGE TRUE
J 0
(-5325 4200);
DISPLAY 0.531915 (-5325 4200);
PAINT GREEN (-5325 4200);
DISPLAY INVISIBLE (-5325 4200);
FORCEPROP 1 LAST COMMENT_BODY TRUE
J 0
(-5695 4230);
DISPLAY 0.531915 (-5695 4230);
PAINT GREEN (-5695 4230);
DISPLAY INVISIBLE (-5695 4230);
FORCEPROP 2 LAST PATH I39
J 0
(-5325 4375);
DISPLAY 1.021277 (-5325 4375);
DISPLAY INVISIBLE (-5325 4375);
FORCEADD Q_CAP..1
(-10850 2550);
FORCEPROP 1 LAST PART_NUMBER CH5104KEB02
J 0
(-10800 2400);
DISPLAY 0.617021 (-10800 2400);
PAINT BLUE (-10800 2400);
DISPLAY INVISIBLE (-10800 2400);
FORCEPROP 1 LAST PACK_TYPE C0402
J 0
(-10800 2350);
DISPLAY 0.617021 (-10800 2350);
PAINT SKYBLUE (-10800 2350);
FORCEPROP 1 LAST MATERIAL X6S
J 0
(-10800 2450);
DISPLAY 0.617021 (-10800 2450);
PAINT RED (-10800 2450);
FORCEPROP 1 LAST TOLERANCE 10%
J 0
(-10800 2500);
DISPLAY 0.617021 (-10800 2500);
PAINT SKYBLUE (-10800 2500);
FORCEPROP 1 LAST VALUE 1UF
J 0
(-10800 2600);
DISPLAY 0.617021 (-10800 2600);
PAINT SKYBLUE (-10800 2600);
FORCEPROP 1 LAST VOLTAGE 25V
J 0
(-10800 2550);
DISPLAY 0.617021 (-10800 2550);
PAINT SKYBLUE (-10800 2550);
FORCEPROP 1 LAST LOCATION PC2643
J 0
(-10800 2650);
DISPLAY 0.617021 (-10800 2650);
PAINT AQUA (-10800 2650);
FORCEPROP 1 LASTPIN (-10850 2650) $PN 1
J 0
(-10840 2630);
DISPLAY 0.617021 (-10840 2630);
FORCEPROP 1 LASTPIN (-10850 2450) $PN 2
J 0
(-10840 2430);
DISPLAY 0.617021 (-10840 2430);
FORCEPROP 2 LAST CDS_LIB pure_quanta
J 0
(-10850 2550);
DISPLAY INVISIBLE (-10850 2550);
FORCEPROP 2 LAST SEC_TYPE C0402
J 0
(-10800 2750);
DISPLAY 1.021277 (-10800 2750);
DISPLAY INVISIBLE (-10800 2750);
FORCEPROP 2 LAST BOM_COST VR_PCH
J 0
(-10800 2700);
DISPLAY 0.680851 (-10800 2700);
DISPLAY INVISIBLE (-10800 2700);
FORCEPROP 1 LAST PATH I4
J 0
(-10800 2700);
DISPLAY 0.978723 (-10800 2700);
PAINT WHITE (-10800 2700);
DISPLAY INVISIBLE (-10800 2700);
FORCEPROP 2 LAST SEC 1
J 0
(-10800 2750);
DISPLAY 0.680851 (-10800 2750);
PAINT MONO (-10800 2750);
DISPLAY INVISIBLE (-10800 2750);
FORCEADD Q_CAP..1
(-5050 2425);
FORCEPROP 1 LAST PART_NUMBER TMP_QCH31004KB17
J 0
(-5000 2275);
DISPLAY 0.617021 (-5000 2275);
PAINT BLUE (-5000 2275);
DISPLAY INVISIBLE (-5000 2275);
FORCEPROP 1 LAST VALUE 0.01UF
J 0
(-5000 2475);
DISPLAY 0.617021 (-5000 2475);
PAINT SKYBLUE (-5000 2475);
FORCEPROP 1 LAST VOLTAGE 25V
J 0
(-5000 2425);
DISPLAY 0.617021 (-5000 2425);
PAINT SKYBLUE (-5000 2425);
FORCEPROP 1 LAST TOLERANCE 10%
J 0
(-5000 2375);
DISPLAY 0.617021 (-5000 2375);
PAINT SKYBLUE (-5000 2375);
FORCEPROP 1 LAST PACK_TYPE 0402
J 0
(-5000 2225);
DISPLAY 0.617021 (-5000 2225);
PAINT SKYBLUE (-5000 2225);
FORCEPROP 1 LAST MATERIAL X7R
J 0
(-5000 2325);
DISPLAY 0.617021 (-5000 2325);
PAINT RED (-5000 2325);
FORCEPROP 1 LAST LOCATION PC1421
J 0
(-5000 2525);
DISPLAY 0.617021 (-5000 2525);
PAINT AQUA (-5000 2525);
FORCEPROP 1 LASTPIN (-5050 2525) $PN 1
J 0
(-5040 2505);
DISPLAY 0.787234 (-5040 2505);
PAINT MONO (-5040 2505);
FORCEPROP 1 LASTPIN (-5050 2325) $PN 2
J 0
(-5040 2305);
DISPLAY 0.787234 (-5040 2305);
PAINT MONO (-5040 2305);
FORCEPROP 2 LAST CDS_LIB pure_quanta
J 0
(-5050 2425);
DISPLAY INVISIBLE (-5050 2425);
FORCEPROP 1 LAST PATH I40
J 0
(-5000 2575);
DISPLAY 0.978723 (-5000 2575);
PAINT WHITE (-5000 2575);
DISPLAY INVISIBLE (-5000 2575);
FORCEPROP 0 LAST $SEC 1
J 0
(-5000 2575);
DISPLAY 0.680851 (-5000 2575);
PAINT MONO (-5000 2575);
DISPLAY INVISIBLE (-5000 2575);
FORCEPROP 0 LAST CDS_SEC 1
J 0
(-5000 2575);
DISPLAY 1.021277 (-5000 2575);
DISPLAY INVISIBLE (-5000 2575);
FORCEADD Q_SHORT..1
(-4600 2875);
FORCEPROP 1 LAST PART_NUMBER SHORT6
J 0
(-4675 2985);
DISPLAY 0.617021 (-4675 2985);
PAINT BLUE (-4675 2985);
DISPLAY INVISIBLE (-4675 2985);
FORCEPROP 2 LAST PACK_TYPE SM
J 0
(-4675 3075);
DISPLAY 0.617021 (-4675 3075);
PAINT SKYBLUE (-4675 3075);
FORCEPROP 1 LAST MATERIAL EMPTY
J 0
(-4675 3035);
DISPLAY 0.617021 (-4675 3035);
PAINT RED (-4675 3035);
FORCEPROP 1 LAST LOCATION PJ64
J 0
(-4675 2930);
DISPLAY 0.617021 (-4675 2930);
PAINT AQUA (-4675 2930);
FORCEPROP 0 LASTPIN (-4725 2875) $PN 1
J 2
(-4735 2885);
DISPLAY 0.808511 (-4735 2885);
FORCEPROP 0 LASTPIN (-4475 2875) $PN 2
J 0
(-4465 2885);
DISPLAY 0.808511 (-4465 2885);
FORCEPROP 2 LAST CDS_LIB pure_quanta
J 0
(-4600 2875);
DISPLAY INVISIBLE (-4600 2875);
FORCEPROP 1 LAST NEEDS_NO_SIZE TRUE
J 0
(-4600 2875);
DISPLAY 0.468085 (-4600 2875);
PAINT GREEN (-4600 2875);
DISPLAY INVISIBLE (-4600 2875);
FORCEPROP 2 LAST BOM_COST VR_PCH
J 0
(-4675 3125);
DISPLAY 0.680851 (-4675 3125);
DISPLAY INVISIBLE (-4675 3125);
FORCEPROP 1 LAST PATH I41
J 0
(-4675 3080);
DISPLAY 0.723404 (-4675 3080);
PAINT GREEN (-4675 3080);
DISPLAY INVISIBLE (-4675 3080);
FORCEPROP 0 LAST $SEC 1
J 0
(-4675 3125);
DISPLAY INVISIBLE (-4675 3125);
FORCEPROP 0 LAST CDS_SEC 1
J 0
(-4675 3125);
DISPLAY INVISIBLE (-4675 3125);
FORCEADD Q_CAP..1
(-5475 3425);
FORCEPROP 1 LAST PART_NUMBER CH622KMEA03
J 0
(-5425 3275);
DISPLAY 0.617021 (-5425 3275);
PAINT BLUE (-5425 3275);
DISPLAY INVISIBLE (-5425 3275);
FORCEPROP 1 LAST PACK_TYPE C0805
J 0
(-5425 3225);
DISPLAY 0.617021 (-5425 3225);
PAINT SKYBLUE (-5425 3225);
FORCEPROP 1 LAST TOLERANCE 20%
J 0
(-5425 3375);
DISPLAY 0.617021 (-5425 3375);
PAINT SKYBLUE (-5425 3375);
FORCEPROP 1 LAST VOLTAGE 4V
J 0
(-5425 3425);
DISPLAY 0.617021 (-5425 3425);
PAINT SKYBLUE (-5425 3425);
FORCEPROP 1 LAST VALUE 22UF
J 0
(-5425 3475);
DISPLAY 0.617021 (-5425 3475);
PAINT SKYBLUE (-5425 3475);
FORCEPROP 1 LAST MATERIAL X6S
J 0
(-5425 3325);
DISPLAY 0.617021 (-5425 3325);
PAINT RED (-5425 3325);
FORCEPROP 1 LAST LOCATION PC1255
J 0
(-5425 3525);
DISPLAY 0.617021 (-5425 3525);
PAINT AQUA (-5425 3525);
FORCEPROP 2 LAST BOM_COST VR_PCH
J 0
(-5425 3575);
DISPLAY 0.680851 (-5425 3575);
DISPLAY INVISIBLE (-5425 3575);
FORCEPROP 2 LAST CDS_LIB pure_quanta
J 0
(-5475 3425);
DISPLAY INVISIBLE (-5475 3425);
FORCEPROP 1 LAST PATH I42
J 0
(-5425 3575);
DISPLAY 0.978723 (-5425 3575);
PAINT WHITE (-5425 3575);
DISPLAY INVISIBLE (-5425 3575);
FORCEPROP 2 LAST $SEC 1
J 0
(-5425 3625);
DISPLAY 0.680851 (-5425 3625);
PAINT MONO (-5425 3625);
DISPLAY INVISIBLE (-5425 3625);
FORCEPROP 2 LAST CDS_SEC 1
J 0
(-5425 3625);
DISPLAY 1.021277 (-5425 3625);
DISPLAY INVISIBLE (-5425 3625);
FORCEPROP 1 LASTPIN (-5475 3525) $PN 1
J 0
(-5465 3505);
DISPLAY 0.787234 (-5465 3505);
PAINT MONO (-5465 3505);
DISPLAY INVISIBLE (-5465 3505);
FORCEPROP 1 LASTPIN (-5475 3325) $PN 2
J 0
(-5465 3305);
DISPLAY 0.787234 (-5465 3305);
PAINT MONO (-5465 3305);
DISPLAY INVISIBLE (-5465 3305);
FORCEADD Q_CAP..1
(-5100 3425);
FORCEPROP 1 LAST PART_NUMBER CH622KMEA03
J 0
(-5050 3275);
DISPLAY 0.617021 (-5050 3275);
PAINT BLUE (-5050 3275);
DISPLAY INVISIBLE (-5050 3275);
FORCEPROP 1 LAST TOLERANCE 20%
J 0
(-5050 3375);
DISPLAY 0.617021 (-5050 3375);
PAINT SKYBLUE (-5050 3375);
FORCEPROP 1 LAST VALUE 22UF
J 0
(-5050 3475);
DISPLAY 0.617021 (-5050 3475);
PAINT SKYBLUE (-5050 3475);
FORCEPROP 1 LAST PACK_TYPE C0805
J 0
(-5050 3225);
DISPLAY 0.617021 (-5050 3225);
PAINT SKYBLUE (-5050 3225);
FORCEPROP 1 LAST VOLTAGE 4V
J 0
(-5050 3425);
DISPLAY 0.617021 (-5050 3425);
PAINT SKYBLUE (-5050 3425);
FORCEPROP 1 LAST MATERIAL X6S
J 0
(-5050 3325);
DISPLAY 0.617021 (-5050 3325);
PAINT RED (-5050 3325);
FORCEPROP 1 LAST LOCATION PC1256
J 0
(-5050 3525);
DISPLAY 0.617021 (-5050 3525);
PAINT AQUA (-5050 3525);
FORCEPROP 2 LAST CDS_LIB pure_quanta
J 0
(-5100 3425);
DISPLAY INVISIBLE (-5100 3425);
FORCEPROP 2 LAST BOM_COST VR_PCH
J 0
(-5050 3575);
DISPLAY 0.680851 (-5050 3575);
DISPLAY INVISIBLE (-5050 3575);
FORCEPROP 1 LAST PATH I43
J 0
(-5050 3575);
DISPLAY 0.978723 (-5050 3575);
PAINT WHITE (-5050 3575);
DISPLAY INVISIBLE (-5050 3575);
FORCEPROP 2 LAST $SEC 1
J 0
(-5050 3625);
DISPLAY 0.680851 (-5050 3625);
PAINT MONO (-5050 3625);
DISPLAY INVISIBLE (-5050 3625);
FORCEPROP 2 LAST CDS_SEC 1
J 0
(-5050 3625);
DISPLAY 1.021277 (-5050 3625);
DISPLAY INVISIBLE (-5050 3625);
FORCEPROP 1 LASTPIN (-5100 3525) $PN 1
J 0
(-5090 3505);
DISPLAY 0.787234 (-5090 3505);
PAINT MONO (-5090 3505);
DISPLAY INVISIBLE (-5090 3505);
FORCEPROP 1 LASTPIN (-5100 3325) $PN 2
J 0
(-5090 3305);
DISPLAY 0.787234 (-5090 3305);
PAINT MONO (-5090 3305);
DISPLAY INVISIBLE (-5090 3305);
FORCEADD Q_CAP..1
(-4725 3425);
FORCEPROP 1 LAST PART_NUMBER CH622KMEA03
J 0
(-4675 3275);
DISPLAY 0.617021 (-4675 3275);
PAINT BLUE (-4675 3275);
DISPLAY INVISIBLE (-4675 3275);
FORCEPROP 1 LAST PACK_TYPE C0805
J 0
(-4675 3225);
DISPLAY 0.617021 (-4675 3225);
PAINT SKYBLUE (-4675 3225);
FORCEPROP 1 LAST MATERIAL X6S
J 0
(-4675 3325);
DISPLAY 0.617021 (-4675 3325);
PAINT RED (-4675 3325);
FORCEPROP 1 LAST TOLERANCE 20%
J 0
(-4675 3375);
DISPLAY 0.617021 (-4675 3375);
PAINT SKYBLUE (-4675 3375);
FORCEPROP 1 LAST VALUE 22UF
J 0
(-4675 3475);
DISPLAY 0.617021 (-4675 3475);
PAINT SKYBLUE (-4675 3475);
FORCEPROP 1 LAST VOLTAGE 4V
J 0
(-4675 3425);
DISPLAY 0.617021 (-4675 3425);
PAINT SKYBLUE (-4675 3425);
FORCEPROP 1 LAST LOCATION PC1257
J 0
(-4675 3525);
DISPLAY 0.617021 (-4675 3525);
PAINT AQUA (-4675 3525);
FORCEPROP 2 LAST BOM_COST VR_PCH
J 0
(-4675 3575);
DISPLAY 0.680851 (-4675 3575);
DISPLAY INVISIBLE (-4675 3575);
FORCEPROP 2 LAST CDS_LIB pure_quanta
J 0
(-4725 3425);
DISPLAY INVISIBLE (-4725 3425);
FORCEPROP 1 LAST PATH I44
J 0
(-4675 3575);
DISPLAY 0.978723 (-4675 3575);
PAINT WHITE (-4675 3575);
DISPLAY INVISIBLE (-4675 3575);
FORCEPROP 2 LAST $SEC 1
J 0
(-4675 3625);
DISPLAY 0.680851 (-4675 3625);
PAINT MONO (-4675 3625);
DISPLAY INVISIBLE (-4675 3625);
FORCEPROP 2 LAST CDS_SEC 1
J 0
(-4675 3625);
DISPLAY 1.021277 (-4675 3625);
DISPLAY INVISIBLE (-4675 3625);
FORCEPROP 1 LASTPIN (-4725 3525) $PN 1
J 0
(-4715 3505);
DISPLAY 0.787234 (-4715 3505);
PAINT MONO (-4715 3505);
DISPLAY INVISIBLE (-4715 3505);
FORCEPROP 1 LASTPIN (-4725 3325) $PN 2
J 0
(-4715 3305);
DISPLAY 0.787234 (-4715 3305);
PAINT MONO (-4715 3305);
DISPLAY INVISIBLE (-4715 3305);
FORCEADD Q_RES..2
(-7225 4650);
FORCEPROP 1 LAST PART_NUMBER CS31002FB08
J 0
(-7185 4525);
DISPLAY 0.617021 (-7185 4525);
PAINT BLUE (-7185 4525);
DISPLAY INVISIBLE (-7185 4525);
FORCEPROP 1 LAST VALUE 10K
J 0
(-7180 4725);
DISPLAY 0.617021 (-7180 4725);
PAINT SKYBLUE (-7180 4725);
FORCEPROP 1 LAST WATTAGE 1/16W
J 0
(-7185 4625);
DISPLAY 0.617021 (-7185 4625);
PAINT SKYBLUE (-7185 4625);
FORCEPROP 1 LAST TOLERANCE 1%
J 0
(-7180 4675);
DISPLAY 0.617021 (-7180 4675);
PAINT SKYBLUE (-7180 4675);
FORCEPROP 1 LAST MATERIAL CHIP
J 0
(-7185 4575);
DISPLAY 0.617021 (-7185 4575);
PAINT RED (-7185 4575);
FORCEPROP 1 LAST PACK_TYPE 0402LF
J 0
(-7185 4475);
DISPLAY 0.617021 (-7185 4475);
PAINT SKYBLUE (-7185 4475);
FORCEPROP 1 LAST LOCATION R2407
J 0
(-7180 4775);
DISPLAY 0.617021 (-7180 4775);
PAINT AQUA (-7180 4775);
FORCEPROP 1 LASTPIN (-7225 4750) $PN 1
J 0
(-7220 4712);
DISPLAY 0.617021 (-7220 4712);
FORCEPROP 1 LASTPIN (-7225 4550) $PN 2
J 0
(-7220 4560);
DISPLAY 0.617021 (-7220 4560);
FORCEPROP 2 LAST CDS_LIB pure_quanta
J 0
(-7225 4650);
DISPLAY INVISIBLE (-7225 4650);
FORCEPROP 2 LAST BOM_COST VR_PCH
J 0
(-7175 4825);
DISPLAY 0.680851 (-7175 4825);
DISPLAY INVISIBLE (-7175 4825);
FORCEPROP 1 LAST PATH I45
J 0
(-7175 4825);
DISPLAY 0.978723 (-7175 4825);
PAINT WHITE (-7175 4825);
DISPLAY INVISIBLE (-7175 4825);
FORCEPROP 0 LAST $SEC 1
J 0
(-7175 4875);
DISPLAY 0.680851 (-7175 4875);
PAINT MONO (-7175 4875);
DISPLAY INVISIBLE (-7175 4875);
FORCEPROP 0 LAST CDS_SEC 1
J 0
(-7175 4875);
DISPLAY 0.680851 (-7175 4875);
DISPLAY INVISIBLE (-7175 4875);
FORCEADD UNIVERSAL_POWER..1
(-7225 4900);
FORCEPROP 3 LASTPIN (-7225 4850) SIG_NAME P3V3_AUX\g
J 0
(-7215 4860);
DISPLAY 0.659574 (-7215 4860);
PAINT MONO (-7215 4860);
DISPLAY INVISIBLE (-7215 4860);
FORCEPROP 1 LAST HDL_POWER P3V3_AUX
J 1
(-7225 4950);
DISPLAY 0.617021 (-7225 4950);
PAINT GREEN (-7225 4950);
FORCEPROP 2 LAST CDS_LIB logical_power
J 0
(-7225 4900);
DISPLAY INVISIBLE (-7225 4900);
FORCEPROP 1 LAST PATH I46
J 0
(-7175 4925);
DISPLAY 0.872340 (-7175 4925);
PAINT AQUA (-7175 4925);
DISPLAY INVISIBLE (-7175 4925);
FORCEADD UNIVERSAL_GND..1
(-3900 1575);
FORCEPROP 3 LASTPIN (-3900 1625) SIG_NAME GND\g
J 0
(-3890 1635);
DISPLAY 0.659574 (-3890 1635);
PAINT MONO (-3890 1635);
DISPLAY INVISIBLE (-3890 1635);
FORCEPROP 2 LAST CDS_LIB logical_power
J 0
(-3900 1575);
DISPLAY INVISIBLE (-3900 1575);
FORCEPROP 1 LAST HDL_POWER GND
J 1
(-3875 1500);
DISPLAY 0.872340 (-3875 1500);
PAINT GREEN (-3875 1500);
DISPLAY INVISIBLE (-3875 1500);
FORCEPROP 1 LAST PATH I47
J 0
(-3825 1575);
DISPLAY 0.872340 (-3825 1575);
PAINT AQUA (-3825 1575);
DISPLAY INVISIBLE (-3825 1575);
FORCEADD UNIVERSAL_GND..1
(-4325 3050);
FORCEPROP 3 LASTPIN (-4325 3100) SIG_NAME GND\g
J 0
(-4315 3110);
DISPLAY 0.659574 (-4315 3110);
PAINT MONO (-4315 3110);
DISPLAY INVISIBLE (-4315 3110);
FORCEPROP 2 LAST CDS_LIB logical_power
J 0
(-4325 3050);
DISPLAY INVISIBLE (-4325 3050);
FORCEPROP 1 LAST HDL_POWER GND
J 1
(-4300 2975);
DISPLAY 0.872340 (-4300 2975);
PAINT GREEN (-4300 2975);
DISPLAY INVISIBLE (-4300 2975);
FORCEPROP 1 LAST PATH I48
J 0
(-4250 3050);
DISPLAY 0.872340 (-4250 3050);
PAINT AQUA (-4250 3050);
DISPLAY INVISIBLE (-4250 3050);
FORCEADD Q_CAPP..1
(-4325 3425);
FORCEPROP 1 LAST PART_NUMBER CC75601MD16
J 0
(-4275 3225);
DISPLAY 0.638298 (-4275 3225);
DISPLAY INVISIBLE (-4275 3225);
FORCEPROP 1 LAST MATERIAL OSCON
J 0
(-4275 3325);
DISPLAY 0.638298 (-4275 3325);
FORCEPROP 1 LAST PACK_TYPE THLF
J 0
(-4275 3275);
DISPLAY 0.638298 (-4275 3275);
FORCEPROP 1 LAST VALUE 560UF
J 0
(-4275 3475);
DISPLAY 0.638298 (-4275 3475);
FORCEPROP 1 LAST TOLERANCE 20%
J 0
(-4275 3425);
DISPLAY 0.638298 (-4275 3425);
FORCEPROP 1 LAST VOLTAGE 6.3V
J 0
(-4275 3375);
DISPLAY 0.638298 (-4275 3375);
FORCEPROP 1 LAST LOCATION PC1258
J 0
(-4275 3525);
DISPLAY 0.638298 (-4275 3525);
FORCEPROP 2 LAST BOM_COST VR_PCH
J 0
(-4275 3575);
DISPLAY 0.680851 (-4275 3575);
DISPLAY INVISIBLE (-4275 3575);
FORCEPROP 2 LAST CDS_LIB pure_quanta
J 0
(-4325 3425);
DISPLAY INVISIBLE (-4325 3425);
FORCEPROP 1 LAST PATH I49
J 0
(-4275 3575);
DISPLAY 0.978723 (-4275 3575);
DISPLAY INVISIBLE (-4275 3575);
FORCEPROP 0 LAST $SEC 1
J 0
(-4275 3575);
DISPLAY 0.680851 (-4275 3575);
PAINT MONO (-4275 3575);
DISPLAY INVISIBLE (-4275 3575);
FORCEPROP 2 LAST CDS_SEC 1
J 0
(-4275 3625);
DISPLAY 1.021277 (-4275 3625);
DISPLAY INVISIBLE (-4275 3625);
FORCEPROP 1 LASTPIN (-4325 3525) $PN 1
J 0
(-4315 3510);
DISPLAY 0.787234 (-4315 3510);
PAINT MONO (-4315 3510);
DISPLAY INVISIBLE (-4315 3510);
FORCEPROP 1 LASTPIN (-4325 3325) $PN 2
J 0
(-4315 3310);
DISPLAY 0.787234 (-4315 3310);
PAINT MONO (-4315 3310);
DISPLAY INVISIBLE (-4315 3310);
FORCEADD Q_RES..2
(-10850 2975);
FORCEPROP 1 LAST PART_NUMBER CS00002JB13
J 0
(-10810 2850);
DISPLAY 0.617021 (-10810 2850);
PAINT BLUE (-10810 2850);
DISPLAY INVISIBLE (-10810 2850);
FORCEPROP 1 LAST PACK_TYPE 0402LF
J 0
(-10810 2800);
DISPLAY 0.617021 (-10810 2800);
PAINT SKYBLUE (-10810 2800);
FORCEPROP 1 LAST TOLERANCE 5%
J 0
(-10805 3000);
DISPLAY 0.617021 (-10805 3000);
PAINT SKYBLUE (-10805 3000);
FORCEPROP 1 LAST VALUE 0
J 0
(-10805 3050);
DISPLAY 0.617021 (-10805 3050);
PAINT SKYBLUE (-10805 3050);
FORCEPROP 1 LAST WATTAGE 1/16W
J 0
(-10810 2950);
DISPLAY 0.617021 (-10810 2950);
PAINT SKYBLUE (-10810 2950);
FORCEPROP 1 LAST MATERIAL CHIP
J 0
(-10810 2900);
DISPLAY 0.617021 (-10810 2900);
PAINT RED (-10810 2900);
FORCEPROP 1 LAST LOCATION PR1335
J 0
(-10805 3100);
DISPLAY 0.617021 (-10805 3100);
PAINT AQUA (-10805 3100);
FORCEPROP 1 LASTPIN (-10850 3075) $PN 1
J 0
(-10845 3037);
DISPLAY 0.617021 (-10845 3037);
FORCEPROP 1 LASTPIN (-10850 2875) $PN 2
J 0
(-10845 2885);
DISPLAY 0.617021 (-10845 2885);
FORCEPROP 2 LAST CDS_LIB pure_quanta
J 0
(-10850 2975);
PAINT MONO (-10850 2975);
DISPLAY INVISIBLE (-10850 2975);
FORCEPROP 1 LAST PATH I5
J 0
(-10800 3150);
DISPLAY 0.978723 (-10800 3150);
PAINT WHITE (-10800 3150);
DISPLAY INVISIBLE (-10800 3150);
FORCEPROP 2 LAST $SEC 1
J 0
(-10800 3200);
DISPLAY 0.680851 (-10800 3200);
PAINT MONO (-10800 3200);
DISPLAY INVISIBLE (-10800 3200);
FORCEPROP 2 LAST CDS_SEC 1
J 0
(-10800 3200);
DISPLAY 1.021277 (-10800 3200);
DISPLAY INVISIBLE (-10800 3200);
FORCEADD UNIVERSAL_POWER..1
(-3900 3850);
FORCEPROP 3 LASTPIN (-3900 3800) SIG_NAME PVPP_HBM_CPU0\g
J 0
(-3890 3810);
DISPLAY 0.659574 (-3890 3810);
PAINT MONO (-3890 3810);
DISPLAY INVISIBLE (-3890 3810);
FORCEPROP 1 LAST HDL_POWER PVPP_HBM_CPU0
J 1
(-3900 3900);
DISPLAY 0.617021 (-3900 3900);
PAINT GREEN (-3900 3900);
FORCEPROP 2 LAST CDS_LIB logical_power
J 0
(-3900 3850);
DISPLAY INVISIBLE (-3900 3850);
FORCEPROP 1 LAST PATH I50
J 0
(-3850 3875);
DISPLAY 0.872340 (-3850 3875);
PAINT AQUA (-3850 3875);
DISPLAY INVISIBLE (-3850 3875);
FORCEADD UNIVERSAL_POWER..1
(-10850 3125);
FORCEPROP 3 LASTPIN (-10850 3075) SIG_NAME P3V3_AUX\g
J 0
(-10840 3085);
DISPLAY 0.659574 (-10840 3085);
PAINT MONO (-10840 3085);
DISPLAY INVISIBLE (-10840 3085);
FORCEPROP 1 LAST HDL_POWER P3V3_AUX
J 1
(-10850 3175);
DISPLAY 0.617021 (-10850 3175);
PAINT GREEN (-10850 3175);
FORCEPROP 2 LAST CDS_LIB logical_power
J 0
(-10850 3125);
DISPLAY INVISIBLE (-10850 3125);
FORCEPROP 1 LAST PATH I6
J 0
(-10800 3150);
DISPLAY 0.872340 (-10800 3150);
PAINT AQUA (-10800 3150);
DISPLAY INVISIBLE (-10800 3150);
FORCEADD Q_CAP..1
(-11425 4350);
FORCEPROP 1 LAST PART_NUMBER CH6223MEA01
J 0
(-11375 4150);
DISPLAY 0.617021 (-11375 4150);
PAINT BLUE (-11375 4150);
DISPLAY INVISIBLE (-11375 4150);
FORCEPROP 1 LAST VOLTAGE 16V
J 0
(-11375 4350);
DISPLAY 0.617021 (-11375 4350);
PAINT SKYBLUE (-11375 4350);
FORCEPROP 1 LAST VALUE 22UF
J 0
(-11375 4400);
DISPLAY 0.617021 (-11375 4400);
PAINT SKYBLUE (-11375 4400);
FORCEPROP 1 LAST TOLERANCE 20%
J 0
(-11375 4300);
DISPLAY 0.617021 (-11375 4300);
PAINT SKYBLUE (-11375 4300);
FORCEPROP 1 LAST MATERIAL X6S
J 0
(-11375 4250);
DISPLAY 0.617021 (-11375 4250);
PAINT RED (-11375 4250);
FORCEPROP 1 LAST PACK_TYPE C0805
J 0
(-11375 4200);
DISPLAY 0.617021 (-11375 4200);
PAINT SKYBLUE (-11375 4200);
FORCEPROP 1 LAST LOCATION PC831
J 0
(-11375 4450);
DISPLAY 0.617021 (-11375 4450);
PAINT AQUA (-11375 4450);
FORCEPROP 1 LASTPIN (-11425 4450) $PN 1
J 0
(-11415 4430);
DISPLAY 0.617021 (-11415 4430);
PAINT MONO (-11415 4430);
FORCEPROP 1 LASTPIN (-11425 4250) $PN 2
J 0
(-11415 4230);
DISPLAY 0.617021 (-11415 4230);
PAINT MONO (-11415 4230);
FORCEPROP 2 LAST BOM_COST VR_PCH
J 0
(-11375 4500);
DISPLAY 0.680851 (-11375 4500);
DISPLAY INVISIBLE (-11375 4500);
FORCEPROP 2 LAST CDS_LIB pure_quanta
J 0
(-11425 4350);
DISPLAY INVISIBLE (-11425 4350);
FORCEPROP 1 LAST PATH I7
J 0
(-11375 4500);
DISPLAY 0.978723 (-11375 4500);
PAINT WHITE (-11375 4500);
DISPLAY INVISIBLE (-11375 4500);
FORCEPROP 0 LAST $SEC 1
J 0
(-11375 4500);
DISPLAY 0.680851 (-11375 4500);
PAINT MONO (-11375 4500);
DISPLAY INVISIBLE (-11375 4500);
FORCEPROP 0 LAST CDS_SEC 1
J 0
(-11375 4500);
DISPLAY 1.021277 (-11375 4500);
DISPLAY INVISIBLE (-11375 4500);
FORCEADD UNIVERSAL_GND..1
(-11425 4000);
FORCEPROP 3 LASTPIN (-11425 4050) SIG_NAME GND\g
J 0
(-11415 4060);
DISPLAY 0.659574 (-11415 4060);
PAINT MONO (-11415 4060);
DISPLAY INVISIBLE (-11415 4060);
FORCEPROP 2 LAST CDS_LIB logical_power
J 0
(-11425 4000);
PAINT MONO (-11425 4000);
DISPLAY INVISIBLE (-11425 4000);
FORCEPROP 1 LAST HDL_POWER GND
J 1
(-11400 3925);
DISPLAY 0.872340 (-11400 3925);
PAINT GREEN (-11400 3925);
DISPLAY INVISIBLE (-11400 3925);
FORCEPROP 1 LAST PATH I8
J 0
(-11350 4000);
DISPLAY 0.872340 (-11350 4000);
PAINT AQUA (-11350 4000);
DISPLAY INVISIBLE (-11350 4000);
FORCEADD Q_RES..1
(-10950 3800);
FORCEPROP 1 LAST PART_NUMBER CS31002FB08
J 0
(-11100 3875);
DISPLAY 0.617021 (-11100 3875);
PAINT BLUE (-11100 3875);
DISPLAY INVISIBLE (-11100 3875);
FORCEPROP 1 LAST VALUE 10K
J 2
(-10725 3800);
DISPLAY 0.617021 (-10725 3800);
PAINT SKYBLUE (-10725 3800);
FORCEPROP 1 LAST TOLERANCE 1%
J 0
(-10700 3800);
DISPLAY 0.617021 (-10700 3800);
PAINT SKYBLUE (-10700 3800);
FORCEPROP 1 LAST PACK_TYPE 0402LF
J 0
(-11100 3900);
DISPLAY 0.617021 (-11100 3900);
PAINT SKYBLUE (-11100 3900);
FORCEPROP 1 LAST WATTAGE 1/16W
J 2
(-10750 3900);
DISPLAY 0.617021 (-10750 3900);
PAINT SKYBLUE (-10750 3900);
FORCEPROP 1 LAST MATERIAL EMPTY
J 0
(-10625 3800);
DISPLAY 0.617021 (-10625 3800);
PAINT RED (-10625 3800);
FORCEPROP 1 LAST LOCATION R2406
J 0
(-11200 3800);
DISPLAY 0.723404 (-11200 3800);
PAINT AQUA (-11200 3800);
FORCEPROP 1 LASTPIN (-11050 3800) $PN 1
J 0
(-11038 3812);
DISPLAY 0.617021 (-11038 3812);
FORCEPROP 1 LASTPIN (-10850 3800) $PN 2
J 0
(-10888 3812);
DISPLAY 0.617021 (-10888 3812);
FORCEPROP 2 LAST CDS_LIB pure_quanta
J 0
(-10950 3800);
PAINT MONO (-10950 3800);
DISPLAY INVISIBLE (-10950 3800);
FORCEPROP 1 LAST PATH I9
J 0
(-11000 3950);
DISPLAY 0.978723 (-11000 3950);
PAINT WHITE (-11000 3950);
DISPLAY INVISIBLE (-11000 3950);
FORCEPROP 2 LAST $SEC 1
J 0
(-11000 4000);
DISPLAY 0.680851 (-11000 4000);
PAINT MONO (-11000 4000);
DISPLAY INVISIBLE (-11000 4000);
FORCEPROP 2 LAST CDS_SEC 1
J 0
(-11000 4000);
DISPLAY 1.021277 (-11000 4000);
DISPLAY INVISIBLE (-11000 4000);
FORCEADD DNS..2
(-10925 3800);
PAINT RED (-10925 3800);
FORCEPROP 2 LAST CDS_LIB mstr_misc
J 0
(-10925 3800);
PAINT MONO (-10925 3800);
DISPLAY INVISIBLE (-10925 3800);
FORCEPROP 1 LAST COMMENT_BODY TRUE
R 1
J 0
(-10850 3575);
DISPLAY 0.872340 (-10850 3575);
PAINT GREEN (-10850 3575);
DISPLAY INVISIBLE (-10850 3575);
FORCEADD DNS..2
(-10375 3375);
PAINT RED (-10375 3375);
FORCEPROP 2 LAST CDS_LIB mstr_misc
J 0
(-10375 3375);
PAINT MONO (-10375 3375);
DISPLAY INVISIBLE (-10375 3375);
FORCEPROP 1 LAST COMMENT_BODY TRUE
R 1
J 0
(-10300 3150);
DISPLAY 0.872340 (-10300 3150);
PAINT GREEN (-10300 3150);
DISPLAY INVISIBLE (-10300 3150);
FORCEADD DNS..2
(-6300 2175);
PAINT RED (-6300 2175);
FORCEPROP 1 LAST COMMENT_BODY TRUE
R 1
J 0
(-6225 1950);
DISPLAY 0.872340 (-6225 1950);
PAINT GREEN (-6225 1950);
DISPLAY INVISIBLE (-6225 1950);
FORCEPROP 2 LAST CDS_LIB mstr_misc
J 0
(-6300 2175);
DISPLAY INVISIBLE (-6300 2175);
FORCEADD DNS..2
(-6325 2475);
PAINT RED (-6325 2475);
FORCEPROP 1 LAST COMMENT_BODY TRUE
R 1
J 0
(-6250 2250);
DISPLAY 0.872340 (-6250 2250);
PAINT GREEN (-6250 2250);
DISPLAY INVISIBLE (-6250 2250);
FORCEPROP 2 LAST CDS_LIB mstr_misc
J 0
(-6325 2475);
DISPLAY INVISIBLE (-6325 2475);
FORCEADD QUANTA_TITLE_BLOCK_C..1
(-3200 675);
FORCEPROP 0 LAST CDS_CON_LAST_MODIFIED Fri Aug 25 14:04:51 2023
J 0
(-5085 690);
DISPLAY INVISIBLE (-5085 690);
FORCEPROP 1 LAST CUSTOM_TXT_CDS <CON_LAST_MODIFIED>
J 0
(-5085 690);
DISPLAY 0.978723 (-5085 690);
FORCEPROP 2 LAST CUSTOM_TXT_CDS <XR_PAGE_TITLE>
J 0
(-11090 5925);
DISPLAY 0.638298 (-11090 5925);
PAINT PINK (-11090 5925);
DISPLAY INVISIBLE (-11090 5925);
FORCEPROP 1 LAST CUSTOM_TXT_CDS <NAME_2>
J 0
(-6375 725);
FORCEPROP 1 LAST CUSTOM_TXT_CDS <NAME_1>
J 0
(-6375 850);
FORCEPROP 1 LAST CUSTOM_TXT_CDS <Q_NUMBER>
J 0
(-4603 778);
DISPLAY 1.212766 (-4603 778);
FORCEPROP 1 LAST CUSTOM_TXT_CDS <Q_PROJ>
J 0
(-5582 777);
DISPLAY 1.212766 (-5582 777);
FORCEPROP 1 LAST CUSTOM_TXT_CDS <Q_REV>
J 0
(-3384 778);
DISPLAY 1.212766 (-3384 778);
FORCEPROP 1 LAST CUSTOM_TXT_CDS <CON_PAGE_NUM> OF <CON_TOTAL_PAGES>
J 0
(-3646 693);
DISPLAY 0.978723 (-3646 693);
FORCEPROP 1 LAST Q_TITLE PVPP_HBM_CPU0
J 0
(-12500 725);
DISPLAY 2.446809 (-12500 725);
PAINT GREEN (-12500 725);
FORCEPROP 1 LAST Q_DEPT 
J 1
(-6963 724);
DISPLAY 1.957447 (-6963 724);
PAINT GREEN (-6963 724);
FORCEPROP 2 LAST CDS_XR_PAGE_TITLE CR-281 : @S9S_MB_2U_LIB.S9S_MB_2U(SCH_1):PAGE281
J 0
(-11090 5925);
DISPLAY 0.638298 (-11090 5925);
PAINT PINK (-11090 5925);
DISPLAY INVISIBLE (-11090 5925);
FORCEPROP 1 LAST COMMENT_BODY TRUE
J 0
(-3188 662);
DISPLAY 0.978723 (-3188 662);
PAINT GREEN (-3188 662);
DISPLAY INVISIBLE (-3188 662);
FORCEPROP 2 LAST PAGE_BORDER TRUE
J 0
(-11090 5925);
DISPLAY 0.638298 (-11090 5925);
PAINT PINK (-11090 5925);
DISPLAY INVISIBLE (-11090 5925);
FORCEPROP 1 LAST CDS_LMAN_SYM_OUTLINE -9475,6775,100,-125
J 0
(-3200 675);
DISPLAY 0.468085 (-3200 675);
PAINT GREEN (-3200 675);
DISPLAY INVISIBLE (-3200 675);
FORCEPROP 2 LAST CDS_LIB pure_quanta
J 0
(-3200 675);
DISPLAY INVISIBLE (-3200 675);
WIRE 16 -1 (-11750 3825)(-11750 3800);
WIRE 16 -1 (-11425 4600)(-11425 4750);
WIRE 16 -1 (-10975 4600)(-11425 4600);
WIRE 16 -1 (-11425 4450)(-11425 4600);
WIRE 16 -1 (-7225 4750)(-7225 4850);
WIRE 16 -1 (-3900 3625)(-3900 3800);
WIRE 16 -1 (-3900 3625)(-4325 3625);
WIRE 16 -1 (-3900 3625)(-3900 2875);
WIRE 16 -1 (-10850 2450)(-10850 2325);
WIRE 16 -1 (-11425 4125)(-11425 4050);
WIRE 16 -1 (-10975 4125)(-11425 4125);
WIRE 16 -1 (-11425 4250)(-11425 4125);
WIRE 16 -1 (-9775 2425)(-9775 2325);
WIRE 16 -1 (-10375 3225)(-10275 3225);
WIRE 16 -1 (-10375 3300)(-10375 3225);
WIRE 16 -1 (-10275 3300)(-10275 3225);
WIRE 16 -1 (-9175 3350)(-9175 3325);
WIRE 16 -1 (-9175 3350)(-9550 3350);
WIRE 16 -1 (-8125 2525)(-8125 2775);
WIRE 16 -1 (-8000 2475)(-8000 2375);
WIRE 16 -1 (-6325 4200)(-6325 4150);
WIRE 16 -1 (-6700 4200)(-6325 4200);
WIRE 16 -1 (-3900 1900)(-3900 1625);
WIRE 16 -1 (-4475 1900)(-3900 1900);
WIRE 16 -1 (-4325 3200)(-4325 3100);
WIRE 16 -1 (-4325 3200)(-4725 3200);
WIRE 16 -1 (-4325 3200)(-4325 3325);
WIRE 16 -1 (-3900 2875)(-4475 2875);
WIRE 16 -1 (-4325 3525)(-4325 3625);
WIRE 16 -1 (-4725 3525)(-4725 3625);
WIRE 16 -1 (-4325 3625)(-4725 3625);
WIRE 16 -1 (-5100 3525)(-5100 3625);
WIRE 16 -1 (-5100 3625)(-4725 3625);
WIRE 16 -1 (-5475 3525)(-5475 3625);
WIRE 16 -1 (-5475 3625)(-5100 3625);
WIRE 16 -1 (-5900 3525)(-5900 3625);
WIRE 16 -1 (-5900 3625)(-5475 3625);
WIRE 16 -1 (-6425 3625)(-5900 3625);
WIRE 16 2175 (-5325 5700)(-3447 5700);
WIRE 16 2175 (-3447 6731)(-3447 5700);
WIRE 16 2175 (-5325 6731)(-5325 5700);
WIRE 16 2175 (-5325 6731)(-3447 6731);
WIRE 16 -1 (-4725 3200)(-4725 3325);
WIRE 16 -1 (-5100 3325)(-5100 3200);
WIRE 16 -1 (-5100 3200)(-4725 3200);
WIRE 16 -1 (-5475 3325)(-5475 3200);
WIRE 16 -1 (-5475 3200)(-5100 3200);
WIRE 16 -1 (-5900 3200)(-5475 3200);
WIRE 16 -1 (-5900 3325)(-5900 3200);
WIRE 16 -1 (-5050 2875)(-5050 2525);
WIRE 16 -1 (-4725 2875)(-5050 2875);
WIRE 16 -1 (-5500 2700)(-6250 2700);
WIRE 16 -1 (-5500 2875)(-5500 2700);
WIRE 16 -1 (-5050 2875)(-5500 2875);
WIRE 16 -1 (-5500 2950)(-5500 2875);
WIRE 16 -1 (-6300 2950)(-5500 2950);
FORCEPROP 2 LAST SIG_NAME SH_PVPP_HBM_CPU0_P
J 0
(-5860 2960);
DISPLAY 0.808511 (-5860 2960);
WIRE 16 -1 (-6250 2475)(-5550 2475);
FORCEPROP 2 LAST SIG_NAME FM_HBM_VPP_SEL_CPU0_D
J 0
(-5910 2385);
DISPLAY 0.617021 (-5910 2385);
WIRE 16 -1 (-5550 2425)(-5550 2475);
WIRE 16 -1 (-6325 2425)(-5550 2425);
WIRE 16 -1 (-6325 2325)(-6325 2425);
WIRE 16 -1 (-5050 1900)(-4725 1900);
WIRE 16 -1 (-5050 2325)(-5050 1900);
WIRE 16 -1 (-6325 2025)(-6325 1900);
WIRE 16 -1 (-6325 1900)(-5050 1900);
FORCEPROP 2 LAST SIG_NAME SH_PVPP_HBM_CPU0_N
J 0
(-5860 1910);
DISPLAY 0.808511 (-5860 1910);
WIRE 16 -1 (-7125 3025)(-8225 3025);
WIRE 16 -1 (-7000 1900)(-6325 1900);
WIRE 16 -1 (-7000 2350)(-7000 1900);
WIRE 16 -1 (-7125 1900)(-7000 1900);
WIRE 16 -1 (-7125 3025)(-7125 1900);
WIRE 16 -1 (-7500 1900)(-7125 1900);
WIRE 16 -1 (-7500 2375)(-7500 1900);
WIRE 16 -1 (-5550 2125)(-6175 2125);
FORCEPROP 2 LAST SIG_NAME FM_HBM2_HBM3_VPP_SEL
J 0
(-6135 2135);
DISPLAY 0.617021 (-6135 2135);
WIRE 16 -1 (-5700 4325)(-6700 4325);
FORCEPROP 2 LAST SIG_NAME PWRGD_PVPP_HBM_CPU0
J 0
(-6385 4335);
DISPLAY 0.617021 (-6385 4335);
WIRE 16 -1 (-7125 4200)(-6900 4200);
WIRE 16 -1 (-7125 4325)(-7125 4200);
WIRE 16 -1 (-6900 4325)(-7125 4325);
WIRE 16 -1 (-7225 4550)(-7225 4325);
WIRE 16 -1 (-7125 4325)(-7225 4325);
WIRE 16 -1 (-7225 4325)(-8150 4325);
FORCEPROP 0 LAST CDS_PHYS_NET_NAME PWRGD_PVPP_HBM_CPU0_R
J 0
(-7835 4365);
PAINT MONO (-7835 4365);
DISPLAY INVISIBLE (-7835 4365);
FORCEPROP 2 LAST SIG_NAME PWRGD_PVPP_HBM_CPU0_R
J 0
(-8060 4335);
DISPLAY 0.765957 (-8060 4335);
WIRE 16 -1 (-8150 4125)(-8150 4325);
WIRE 16 -1 (-8225 4125)(-8150 4125);
WIRE 16 -1 (-6725 2475)(-6450 2475);
WIRE 16 -1 (-6500 2950)(-6725 2950);
WIRE 16 -1 (-6725 2700)(-6725 2475);
WIRE 16 -1 (-6725 2700)(-6450 2700);
WIRE 16 -1 (-6725 2875)(-6725 2700);
WIRE 16 -1 (-6725 2950)(-6725 2875);
WIRE 16 -1 (-7000 2550)(-7000 2875);
WIRE 16 -1 (-7000 2875)(-6725 2875);
WIRE 16 -1 (-7000 3175)(-8225 3175);
FORCEPROP 2 LAST SIG_NAME PVPP_HBM_CPU0_FB
J 0
(-8060 3185);
DISPLAY 0.808511 (-8060 3185);
WIRE 16 -1 (-7000 3175)(-7000 2875);
WIRE 16 -1 (-8150 3925)(-8225 3925);
WIRE 16 -1 (-8150 4025)(-8150 3925);
WIRE 16 -1 (-8150 4025)(-7350 4025);
FORCEPROP 2 LAST SIG_NAME SW_PVPP_HBM_CPU0_BST
J 0
(-8060 4035);
DISPLAY 0.765957 (-8060 4035);
WIRE 16 -1 (-7350 3950)(-7350 4025);
WIRE 16 -1 (-7350 3750)(-7350 3625);
WIRE 16 -1 (-7350 3625)(-6625 3625);
WIRE 16 -1 (-8225 3625)(-7350 3625);
FORCEPROP 2 LAST SIG_NAME SW_PVPP_HBM_CPU0_SW
J 0
(-8060 3635);
DISPLAY 0.765957 (-8060 3635);
WIRE 16 -1 (-7500 2925)(-7500 2575);
WIRE 16 -1 (-8000 2675)(-8000 2925);
WIRE 16 -1 (-8000 2925)(-7500 2925);
WIRE 16 -1 (-8225 2925)(-8000 2925);
FORCEPROP 2 LAST SIG_NAME PVPP_HBM_CPU0_REF
J 0
(-8060 2935);
DISPLAY 0.765957 (-8060 2935);
WIRE 16 -1 (-8125 2825)(-8225 2825);
WIRE 16 -1 (-8125 2825)(-8125 2775);
WIRE 16 -1 (-8225 2775)(-8125 2775);
WIRE 16 -1 (-9025 4075)(-9200 4075);
WIRE 16 -1 (-9200 4125)(-9200 4075);
WIRE 16 -1 (-9025 4125)(-9200 4125);
WIRE 16 -1 (-9200 4125)(-9200 4600);
WIRE 16 -1 (-10125 4600)(-10125 4450);
WIRE 16 -1 (-9200 4600)(-10125 4600);
WIRE 16 -1 (-10550 4450)(-10550 4600);
WIRE 16 -1 (-10125 4600)(-10550 4600);
WIRE 16 -1 (-10550 4600)(-10975 4600);
WIRE 16 -1 (-10975 4450)(-10975 4600);
WIRE 16 -1 (-9025 3425)(-10025 3425);
FORCEPROP 2 LAST SIG_NAME PVPP_HBM_CPU0_MODE
J 0
(-9735 3435);
DISPLAY 0.638298 (-9735 3435);
WIRE 16 -1 (-10025 3350)(-10025 3425);
WIRE 16 -1 (-9750 3350)(-10025 3350);
WIRE 16 -1 (-10975 4250)(-10975 4125);
WIRE 16 -1 (-10550 4125)(-10975 4125);
WIRE 16 -1 (-10550 4250)(-10550 4125);
WIRE 16 -1 (-10125 4125)(-10550 4125);
WIRE 16 -1 (-10125 4250)(-10125 4125);
WIRE 16 -1 (-10250 3800)(-10850 3800);
WIRE 16 -1 (-10250 3625)(-10250 3800);
WIRE 16 -1 (-10250 3625)(-9025 3625);
WIRE 16 -1 (-10275 3625)(-11550 3625);
WIRE 16 -1 (-10250 3625)(-10275 3625);
WIRE 16 -1 (-10275 3500)(-10275 3550);
WIRE 16 -1 (-10275 3550)(-10275 3625);
WIRE 16 -1 (-10375 3550)(-10275 3550);
WIRE 16 -1 (-10375 3500)(-10375 3550);
WIRE 16 -1 (-9775 2825)(-9775 2625);
WIRE 16 -1 (-9025 2825)(-9775 2825);
FORCEPROP 2 LAST SIG_NAME PVPP_HBM_CPU0_CS
J 0
(-9735 2835);
DISPLAY 0.617021 (-9735 2835);
WIRE 16 -1 (-10850 2700)(-10850 2650);
WIRE 16 -1 (-10850 2875)(-10850 2700);
WIRE 16 -1 (-10150 2700)(-10850 2700);
WIRE 16 -1 (-10150 3175)(-10150 2700);
WIRE 16 -1 (-9025 3175)(-10150 3175);
FORCEPROP 2 LAST SIG_NAME PVPP_HBM_CPU0_VCC
J 0
(-9735 3185);
DISPLAY 0.617021 (-9735 3185);
WIRE 16 -1 (-11750 3800)(-11050 3800);
WIRE 16 2175 (-11825 1275)(-10972 1275);
WIRE 16 2175 (-10972 1700)(-10972 1275);
WIRE 16 2175 (-11825 1700)(-11825 1275);
WIRE 16 2175 (-11825 1700)(-10972 1700);
DOT 1 (-3900 3625);
DOT 1 (-4325 3625);
DOT 1 (-4325 3200);
DOT 1 (-4725 3625);
DOT 1 (-5100 3625);
DOT 1 (-5475 3625);
DOT 1 (-4725 3200);
CIRCLE (-4600 2925)(-4387 2925);
PAINT YELLOW (-4600 2925);
DOT 1 (-5100 3200);
DOT 1 (-5050 2875);
DOT 1 (-5475 3200);
DOT 1 (-5500 2875);
DOT 1 (-5900 3625);
CIRCLE (-4600 1925)(-4370 1925);
PAINT YELLOW (-4600 1925);
DOT 1 (-5050 1900);
DOT 1 (-6325 1900);
DOT 1 (-7125 4325);
DOT 1 (-7225 4325);
DOT 1 (-7350 3625);
DOT 1 (-6725 2875);
DOT 1 (-7000 2875);
DOT 1 (-6725 2700);
DOT 1 (-8000 2925);
DOT 1 (-8125 2775);
DOT 1 (-7000 1900);
DOT 1 (-7125 1900);
DOT 1 (-10125 4600);
DOT 1 (-10550 4600);
DOT 1 (-10975 4600);
DOT 1 (-11425 4600);
DOT 1 (-9200 4125);
DOT 1 (-10550 4125);
DOT 1 (-10250 3625);
DOT 1 (-10275 3625);
DOT 1 (-10275 3550);
DOT 1 (-10975 4125);
DOT 1 (-11425 4125);
DOT 1 (-10850 2700);
FORCENOTE
20220804 CHANGE PC1253 TO 680PF FOR TRANSIENT RESPONSE
(-7500 1150) 0;
DISPLAY LEFT (-7500 1150);
DISPLAY 1.595745 (-7500 1150);
PAINT PINK (-7500 1150);
FORCENOTE
PLACE AT CHIPSET SIDE
(-4725 2350) 0;
DISPLAY LEFT (-4725 2350);
DISPLAY 1.021277 (-4725 2350);
FORCENOTE
REMOTE SENSE
(-4725 2425) 0;
DISPLAY LEFT (-4725 2425);
DISPLAY 1.021277 (-4725 2425);
FORCENOTE
SLEW RATE=1.6A/US
(-5311 5892) 0;
DISPLAY LEFT (-5311 5892);
DISPLAY 1.170213 (-5311 5892);
PAINT RED (-5311 5892);
FORCENOTE
TOTAL TOL=2.708VMAX/ 2.530VMIN
(-5309 6267) 0;
DISPLAY LEFT (-5309 6267);
DISPLAY 1.276596 (-5309 6267);
PAINT RED (-5309 6267);
FORCENOTE
CURRENT STEP=4.6A
(-5311 5967) 0;
DISPLAY LEFT (-5311 5967);
DISPLAY 1.170213 (-5311 5967);
PAINT RED (-5311 5967);
FORCENOTE
OCP(IMAX*130%)=8A
(-5311 6042) 0;
DISPLAY LEFT (-5311 6042);
DISPLAY 1.170213 (-5311 6042);
PAINT WHITE (-5311 6042);
FORCENOTE
WORK FREQUENCY=800KHZ
(-5300 5825) 0;
DISPLAY LEFT (-5300 5825);
DISPLAY 1.170213 (-5300 5825);
PAINT WHITE (-5300 5825);
FORCENOTE
PVPP_HBM_CPU0 SPECIFICATION
(-5312 6646) 0;
DISPLAY LEFT (-5312 6646);
DISPLAY 1.468085 (-5312 6646);
PAINT WHITE (-5312 6646);
FORCENOTE
20220808 UPDATE PDG REV 1.6
(-5450 5600) 0;
DISPLAY LEFT (-5450 5600);
DISPLAY 1.595745 (-5450 5600);
FORCENOTE
DC=+/-0.7%
(-5300 6425) 0;
DISPLAY LEFT (-5300 6425);
DISPLAY 1.276596 (-5300 6425);
PAINT RED (-5300 6425);
FORCENOTE
VOUT=2.5V
(-5312 6496) 0;
DISPLAY LEFT (-5312 6496);
DISPLAY 1.170213 (-5312 6496);
PAINT WHITE (-5312 6496);
FORCENOTE
RIPPLE=+/-7MV
(-5312 6346) 0;
DISPLAY LEFT (-5312 6346);
DISPLAY 1.170213 (-5312 6346);
PAINT RED (-5312 6346);
FORCENOTE
PDG REV 1.6
(-5300 5750) 0;
DISPLAY LEFT (-5300 5750);
DISPLAY 1.170213 (-5300 5750);
PAINT WHITE (-5300 5750);
FORCENOTE
TDC=4A
(-5311 6192) 0;
DISPLAY LEFT (-5311 6192);
DISPLAY 1.170213 (-5311 6192);
PAINT WHITE (-5311 6192);
FORCENOTE
MAX CURRENT=5A
(-5311 6117) 0;
DISPLAY LEFT (-5311 6117);
DISPLAY 1.170213 (-5311 6117);
PAINT RED (-5311 6117);
FORCENOTE
RA
(-6475 3050) 0;
DISPLAY LEFT (-6475 3050);
DISPLAY 1.021277 (-6475 3050);
FORCENOTE
2ND 270PF
(-6100 1450) 0;
DISPLAY LEFT (-6100 1450);
DISPLAY 1.276596 (-6100 1450);
PAINT PINK (-6100 1450);
FORCENOTE
3RD 100PF
(-6100 1350) 0;
DISPLAY LEFT (-6100 1350);
DISPLAY 1.276596 (-6100 1350);
PAINT PINK (-6100 1350);
FORCENOTE
PC1253 MAIN 680PF
(-6575 1550) 0;
DISPLAY LEFT (-6575 1550);
DISPLAY 1.276596 (-6575 1550);
PAINT PINK (-6575 1550);
FORCENOTE
20220808 ADD CHANGE LIST
(-7275 1650) 0;
DISPLAY LEFT (-7275 1650);
DISPLAY 1.595745 (-7275 1650);
PAINT PINK (-7275 1650);
FORCENOTE
VOUT=((RA/RB)+1)*0.6=2.634V
(-6925 1800) 0;
DISPLAY LEFT (-6925 1800);
DISPLAY 1.021277 (-6925 1800);
PAINT SKYBLUE (-6925 1800);
FORCENOTE
DCR=5.5M OHM
(-6775 3375) 0;
DISPLAY LEFT (-6775 3375);
DISPLAY 0.808511 (-6775 3375);
FORCENOTE
ISAT=23A@100C
(-6775 3425) 0;
DISPLAY LEFT (-6775 3425);
DISPLAY 0.808511 (-6775 3425);
FORCENOTE
PCMC063T-R68MN
(-6775 3525) 0;
DISPLAY LEFT (-6775 3525);
DISPLAY 0.808511 (-6775 3525);
FORCENOTE
6.5*6.9*3.0
(-6775 3475) 0;
DISPLAY LEFT (-6775 3475);
DISPLAY 0.808511 (-6775 3475);
FORCENOTE
RB
(-6925 2625) 0;
DISPLAY LEFT (-6925 2625);
DISPLAY 1.021277 (-6925 2625);
FORCENOTE
PVPP_HBM_CPU0
(-9525 5575) 0;
DISPLAY LEFT (-9525 5575);
DISPLAY 3.148936 (-9525 5575);
PAINT YELLOW (-9525 5575);
FORCENOTE
2ND 2.2UF
(-10525 1925) 0;
DISPLAY LEFT (-10525 1925);
DISPLAY 1.276596 (-10525 1925);
PAINT PINK (-10525 1925);
FORCENOTE
3RD 1UF
(-10525 1825) 0;
DISPLAY LEFT (-10525 1825);
DISPLAY 1.276596 (-10525 1825);
PAINT PINK (-10525 1825);
FORCENOTE
20220808 ADD CHANGE LIST
(-11700 2125) 0;
DISPLAY LEFT (-11700 2125);
DISPLAY 1.595745 (-11700 2125);
PAINT PINK (-11700 2125);
FORCENOTE
PC2643 MAIN 1UF
(-11000 2025) 0;
DISPLAY LEFT (-11000 2025);
DISPLAY 1.276596 (-11000 2025);
PAINT PINK (-11000 2025);
FORCENOTE
20220804 CHANGE IC TABLE
(-11800 1150) 0;
DISPLAY LEFT (-11800 1150);
DISPLAY 1.595745 (-11800 1150);
PAINT PINK (-11800 1150);
FORCENOTE
3RD AL008633007
(-11775 1350) 0;
DISPLAY LEFT (-11775 1350);
DISPLAY 1.021277 (-11775 1350);
PAINT WHITE (-11775 1350);
FORCENOTE
2ND AL000548006
(-11775 1425) 0;
DISPLAY LEFT (-11775 1425);
DISPLAY 1.021277 (-11775 1425);
PAINT WHITE (-11775 1425);
FORCENOTE
1ST AL053318002
(-11775 1500) 0;
DISPLAY LEFT (-11775 1500);
DISPLAY 1.021277 (-11775 1500);
PAINT WHITE (-11775 1500);
FORCENOTE
IC TABLE
(-11800 1600) 0;
DISPLAY LEFT (-11800 1600);
DISPLAY 1.170213 (-11800 1600);
PAINT WHITE (-11800 1600);
QUIT
